FILE_TYPE = MACRO_DRAWING;
SET COLOR_WIRE YELLOW;
SET COLOR_PROP MONO;
SET COLOR_DOT WHITE;
SET COLOR_ARC YELLOW;
SET COLOR_BODY GREEN;
SET COLOR_NOTE MONO;
SET PROP_DISPLAY VALUE;
SET PAGE_NUMBER P169;
FORCEADD OFFPAGE..2
(1225 2900);
FORCEPROP 2 LAST $XR0 147 
J 0
(1414 2900);
DISPLAY 0.638298 (1414 2900);
PAINT MONO (1414 2900);
FORCEPROP 1 LAST COMMENT_BODY TRUE
J 0
(1180 2805);
DISPLAY 1.170213 (1180 2805);
PAINT GREEN (1180 2805);
DISPLAY INVISIBLE (1180 2805);
FORCEPROP 1 LAST OFFPAGE TRUE
J 0
(1550 2775);
PAINT GREEN (1550 2775);
DISPLAY INVISIBLE (1550 2775);
FORCEPROP 2 LAST PATH I103
J 0
(1425 2950);
PAINT MONO (1425 2950);
DISPLAY INVISIBLE (1425 2950);
FORCEPROP 2 LAST CDS_LIB mstr_standard
J 0
(1225 2900);
DISPLAY 1.361702 (1225 2900);
PAINT ORANGE (1225 2900);
DISPLAY INVISIBLE (1225 2900);
FORCEADD OFFPAGE..1
(-400 4225);
FORCEPROP 2 LAST $XR0 196 
J 0
(-682 4225);
DISPLAY 0.638298 (-682 4225);
PAINT MONO (-682 4225);
FORCEPROP 1 LAST COMMENT_BODY TRUE
J 0
(-275 4125);
DISPLAY 0.978723 (-275 4125);
PAINT GREEN (-275 4125);
DISPLAY INVISIBLE (-275 4125);
FORCEPROP 1 LAST OFFPAGE TRUE
J 0
(-75 4100);
PAINT GREEN (-75 4100);
DISPLAY INVISIBLE (-75 4100);
FORCEPROP 2 LAST PATH I105
J 0
(-675 4275);
PAINT MONO (-675 4275);
DISPLAY INVISIBLE (-675 4275);
FORCEPROP 2 LAST CDS_LIB mstr_standard
J 1
(-400 4225);
PAINT ORANGE (-400 4225);
DISPLAY INVISIBLE (-400 4225);
FORCEADD RES..2
(400 2725);
FORCEPROP 1 LASTPIN (400 2825) $PN 1
J 0
(405 2787);
DISPLAY 0.617021 (405 2787);
PAINT ORANGE (405 2787);
FORCEPROP 1 LASTPIN (400 2625) $PN 2
J 0
(405 2635);
DISPLAY 0.617021 (405 2635);
PAINT ORANGE (405 2635);
FORCEPROP 1 LAST WATTAGE 1/16W
J 0
(440 2700);
DISPLAY 0.617021 (440 2700);
PAINT SKYBLUE (440 2700);
FORCEPROP 1 LAST MATERIAL CHIP
J 0
(440 2650);
DISPLAY 0.617021 (440 2650);
PAINT SKYBLUE (440 2650);
FORCEPROP 1 LAST PACK_TYPE 0402
J 0
(440 2550);
DISPLAY 0.617021 (440 2550);
PAINT SKYBLUE (440 2550);
FORCEPROP 1 LAST TOLERANCE 1%
J 0
(445 2750);
DISPLAY 0.617021 (445 2750);
PAINT SKYBLUE (445 2750);
FORCEPROP 1 LAST VALUE 100.0K
J 0
(445 2800);
DISPLAY 0.617021 (445 2800);
PAINT SKYBLUE (445 2800);
FORCEPROP 1 LAST PART_NUMBER G21796-010
J 0
(440 2600);
DISPLAY 0.617021 (440 2600);
PAINT BLUE (440 2600);
FORCEPROP 1 LAST LOCATION R9G26
J 0
(445 2850);
DISPLAY 0.617021 (445 2850);
PAINT AQUA (445 2850);
FORCEPROP 2 LAST ROOM BMC_VOLT_MONITOR
J 0
(450 2900);
DISPLAY 1.021277 (450 2900);
PAINT ORANGE (450 2900);
DISPLAY INVISIBLE (450 2900);
FORCEPROP 1 LAST PATH I106
J 0
(450 2900);
DISPLAY 0.978723 (450 2900);
PAINT WHITE (450 2900);
DISPLAY INVISIBLE (450 2900);
FORCEPROP 2 LAST CDS_LOCATION R9G26
J 0
(445 2850);
DISPLAY 0.617021 (445 2850);
PAINT AQUA (445 2850);
DISPLAY INVISIBLE (445 2850);
FORCEPROP 2 LAST SEC 1
J 0
(450 2950);
PAINT MONO (450 2950);
DISPLAY INVISIBLE (450 2950);
FORCEPROP 2 LAST BOM_COST SM_HM
J 0
(450 2950);
DISPLAY 1.021277 (450 2950);
PAINT ORANGE (450 2950);
DISPLAY INVISIBLE (450 2950);
FORCEPROP 2 LAST SEC_TYPE 0402
J 0
(450 2950);
DISPLAY 1.021277 (450 2950);
PAINT ORANGE (450 2950);
DISPLAY INVISIBLE (450 2950);
FORCEPROP 2 LAST CDS_LIB mstr_discrete
J 0
(400 2725);
PAINT ORANGE (400 2725);
DISPLAY INVISIBLE (400 2725);
FORCEADD GND..1
(400 2500);
FORCEPROP 3 LASTPIN (400 2550) SIG_NAME GND\g
J 0
(410 2560);
DISPLAY 0.659574 (410 2560);
PAINT MONO (410 2560);
DISPLAY INVISIBLE (410 2560);
FORCEPROP 1 LAST HDL_POWER GND
J 0
(400 2650);
DISPLAY 1.148936 (400 2650);
PAINT GREEN (400 2650);
DISPLAY INVISIBLE (400 2650);
FORCEPROP 1 LAST BODY_TYPE PLUMBING
J 0
(355 2457);
DISPLAY 0.340426 (355 2457);
PAINT GREEN (355 2457);
DISPLAY INVISIBLE (355 2457);
FORCEPROP 1 LAST PATH I107
J 0
(475 2500);
DISPLAY 1.212766 (475 2500);
PAINT GREEN (475 2500);
DISPLAY INVISIBLE (475 2500);
FORCEPROP 1 LAST SIZE 1B
J 0
(475 2450);
DISPLAY 1.148936 (475 2450);
PAINT GREEN (475 2450);
DISPLAY INVISIBLE (475 2450);
FORCEPROP 2 LAST CDS_LIB mstr_symbols
J 0
(400 2500);
PAINT ORANGE (400 2500);
DISPLAY INVISIBLE (400 2500);
FORCEPROP 1 LAST VOLTAGE 0
J 0
(400 2500);
PAINT SKYBLUE (400 2500);
DISPLAY INVISIBLE (400 2500);
FORCEADD CAP..1
(800 2700);
FORCEPROP 1 LAST PART_NUMBER A36094-025
J 0
(850 2550);
DISPLAY 0.617021 (850 2550);
PAINT BLUE (850 2550);
FORCEPROP 1 LAST PACK_TYPE 0402LF
J 0
(850 2500);
DISPLAY 0.617021 (850 2500);
PAINT SKYBLUE (850 2500);
FORCEPROP 1 LAST TOLERANCE 5%
J 0
(850 2650);
DISPLAY 0.617021 (850 2650);
PAINT SKYBLUE (850 2650);
FORCEPROP 1 LASTPIN (800 2800) $PN 1
J 0
(810 2780);
DISPLAY 0.617021 (810 2780);
PAINT ORANGE (810 2780);
FORCEPROP 1 LASTPIN (800 2600) $PN 2
J 0
(810 2580);
DISPLAY 0.617021 (810 2580);
PAINT ORANGE (810 2580);
FORCEPROP 1 LAST MATERIAL COG
J 0
(850 2600);
DISPLAY 0.617021 (850 2600);
PAINT SKYBLUE (850 2600);
FORCEPROP 1 LAST VOLTAGE 50V
J 0
(850 2700);
DISPLAY 0.617021 (850 2700);
PAINT SKYBLUE (850 2700);
FORCEPROP 1 LAST VALUE 10.0PF
J 0
(850 2750);
DISPLAY 0.617021 (850 2750);
PAINT SKYBLUE (850 2750);
FORCEPROP 1 LAST LOCATION C9G22
J 0
(850 2800);
DISPLAY 0.617021 (850 2800);
PAINT AQUA (850 2800);
FORCEPROP 2 LAST ROOM BMC_VOLT_MONITOR
J 0
(850 2850);
DISPLAY 1.021277 (850 2850);
PAINT ORANGE (850 2850);
DISPLAY INVISIBLE (850 2850);
FORCEPROP 1 LAST PATH I108
J 0
(850 2850);
DISPLAY 0.978723 (850 2850);
PAINT WHITE (850 2850);
DISPLAY INVISIBLE (850 2850);
FORCEPROP 2 LAST CDS_LOCATION C9G22
J 0
(850 2800);
DISPLAY 0.617021 (850 2800);
PAINT AQUA (850 2800);
DISPLAY INVISIBLE (850 2800);
FORCEPROP 2 LAST SEC 1
J 0
(850 2900);
DISPLAY 0.680851 (850 2900);
PAINT MONO (850 2900);
DISPLAY INVISIBLE (850 2900);
FORCEPROP 2 LAST BOM_COST SM_HM
J 0
(850 2900);
DISPLAY 1.021277 (850 2900);
PAINT ORANGE (850 2900);
DISPLAY INVISIBLE (850 2900);
FORCEPROP 2 LAST SEC_TYPE 0402LF
J 0
(850 2900);
DISPLAY 1.021277 (850 2900);
PAINT ORANGE (850 2900);
DISPLAY INVISIBLE (850 2900);
FORCEPROP 2 LAST CDS_LIB mstr_discrete
J 0
(800 2700);
PAINT ORANGE (800 2700);
DISPLAY INVISIBLE (800 2700);
FORCEADD GND..1
(800 2500);
FORCEPROP 3 LASTPIN (800 2550) SIG_NAME GND\g
J 0
(810 2560);
DISPLAY 0.659574 (810 2560);
PAINT MONO (810 2560);
DISPLAY INVISIBLE (810 2560);
FORCEPROP 1 LAST HDL_POWER GND
J 0
(800 2650);
DISPLAY 1.148936 (800 2650);
PAINT GREEN (800 2650);
DISPLAY INVISIBLE (800 2650);
FORCEPROP 1 LAST BODY_TYPE PLUMBING
J 0
(755 2457);
DISPLAY 0.340426 (755 2457);
PAINT GREEN (755 2457);
DISPLAY INVISIBLE (755 2457);
FORCEPROP 1 LAST PATH I109
J 0
(875 2500);
DISPLAY 1.212766 (875 2500);
PAINT GREEN (875 2500);
DISPLAY INVISIBLE (875 2500);
FORCEPROP 1 LAST SIZE 1B
J 0
(875 2450);
DISPLAY 1.148936 (875 2450);
PAINT GREEN (875 2450);
DISPLAY INVISIBLE (875 2450);
FORCEPROP 2 LAST CDS_LIB mstr_symbols
J 0
(800 2500);
PAINT ORANGE (800 2500);
DISPLAY INVISIBLE (800 2500);
FORCEPROP 1 LAST VOLTAGE 0
J 0
(800 2500);
PAINT SKYBLUE (800 2500);
DISPLAY INVISIBLE (800 2500);
FORCEADD RES..2
(-2850 1750);
FORCEPROP 1 LAST WATTAGE 1/16W
J 0
(-2810 1725);
DISPLAY 0.617021 (-2810 1725);
PAINT SKYBLUE (-2810 1725);
FORCEPROP 1 LAST VALUE 5.11K
J 0
(-2805 1825);
DISPLAY 0.617021 (-2805 1825);
PAINT SKYBLUE (-2805 1825);
FORCEPROP 1 LASTPIN (-2850 1850) $PN 1
J 0
(-2845 1812);
DISPLAY 0.617021 (-2845 1812);
PAINT MONO (-2845 1812);
FORCEPROP 1 LAST MATERIAL CHIP
J 0
(-2810 1675);
DISPLAY 0.617021 (-2810 1675);
PAINT SKYBLUE (-2810 1675);
FORCEPROP 1 LAST TOLERANCE 1%
J 0
(-2805 1775);
DISPLAY 0.617021 (-2805 1775);
PAINT SKYBLUE (-2805 1775);
FORCEPROP 1 LAST LOCATION R1U47
J 0
(-2805 1875);
DISPLAY 0.617021 (-2805 1875);
PAINT AQUA (-2805 1875);
FORCEPROP 1 LAST PACK_TYPE 0402
J 0
(-2810 1575);
DISPLAY 0.617021 (-2810 1575);
PAINT SKYBLUE (-2810 1575);
FORCEPROP 1 LASTPIN (-2850 1650) $PN 2
J 0
(-2845 1660);
DISPLAY 0.617021 (-2845 1660);
PAINT MONO (-2845 1660);
FORCEPROP 1 LAST PART_NUMBER G21796-140
J 0
(-2810 1625);
DISPLAY 0.617021 (-2810 1625);
PAINT BLUE (-2810 1625);
FORCEPROP 2 LAST ROOM BMC_VOLT_MONITOR
J 0
(-2800 1925);
DISPLAY 1.021277 (-2800 1925);
PAINT ORANGE (-2800 1925);
DISPLAY INVISIBLE (-2800 1925);
FORCEPROP 1 LAST PATH I115
J 0
(-2800 1925);
DISPLAY 1.361702 (-2800 1925);
PAINT WHITE (-2800 1925);
DISPLAY INVISIBLE (-2800 1925);
FORCEPROP 2 LAST CDS_LOCATION R1U47
J 0
(-2805 1875);
DISPLAY 0.617021 (-2805 1875);
PAINT AQUA (-2805 1875);
DISPLAY INVISIBLE (-2805 1875);
FORCEPROP 2 LAST SEC 1
J 0
(-2800 1975);
DISPLAY 0.936170 (-2800 1975);
PAINT MONO (-2800 1975);
DISPLAY INVISIBLE (-2800 1975);
FORCEPROP 2 LAST BOM_COST SM_HM
J 0
(-2800 1975);
DISPLAY 1.021277 (-2800 1975);
PAINT ORANGE (-2800 1975);
DISPLAY INVISIBLE (-2800 1975);
FORCEPROP 2 LAST CDS_LIB mstr_discrete
J 0
(-2850 1750);
DISPLAY 1.361702 (-2850 1750);
PAINT ORANGE (-2850 1750);
DISPLAY INVISIBLE (-2850 1750);
FORCEPROP 2 LAST SEC_TYPE 0402
J 0
(-2800 1975);
PAINT MONO (-2800 1975);
DISPLAY INVISIBLE (-2800 1975);
FORCEADD P5V_STBY..1
(-2850 1975);
FORCEPROP 3 LASTPIN (-2850 1925) SIG_NAME P5V_STBY\g
J 0
(-2840 1935);
DISPLAY 0.659574 (-2840 1935);
PAINT MONO (-2840 1935);
DISPLAY INVISIBLE (-2840 1935);
FORCEPROP 1 LAST HDL_POWER P5V_STBY
J 0
(-3150 1850);
DISPLAY 0.872340 (-3150 1850);
PAINT ORANGE (-3150 1850);
DISPLAY INVISIBLE (-3150 1850);
FORCEPROP 1 LAST BODY_TYPE PLUMBING
J 0
(-2895 1932);
DISPLAY 0.340426 (-2895 1932);
PAINT GREEN (-2895 1932);
DISPLAY INVISIBLE (-2895 1932);
FORCEPROP 1 LAST PATH I119
J 0
(-2805 1977);
DISPLAY 0.340426 (-2805 1977);
PAINT GREEN (-2805 1977);
DISPLAY INVISIBLE (-2805 1977);
FORCEPROP 2 LAST CDS_LIB mstr_symbols
J 0
(-2850 1975);
PAINT ORANGE (-2850 1975);
DISPLAY INVISIBLE (-2850 1975);
FORCEPROP 1 LAST SIZE 1B
J 0
(-2805 1997);
DISPLAY 0.340426 (-2805 1997);
PAINT GREEN (-2805 1997);
DISPLAY INVISIBLE (-2805 1997);
FORCEPROP 1 LAST VOLTAGE 5.0V
J 0
(-2895 1932);
DISPLAY 0.340426 (-2895 1932);
PAINT SKYBLUE (-2895 1932);
DISPLAY INVISIBLE (-2895 1932);
FORCEADD P1V05_PCH_STBY..1
(-4825 3775);
FORCEPROP 3 LASTPIN (-4825 3725) SIG_NAME P1V05_PCH_STBY\g
J 0
(-4815 3735);
DISPLAY 0.659574 (-4815 3735);
PAINT MONO (-4815 3735);
DISPLAY INVISIBLE (-4815 3735);
FORCEPROP 1 LAST HDL_POWER P1V05_PCH_STBY
J 0
(-4825 3825);
DISPLAY 0.872340 (-4825 3825);
PAINT GREEN (-4825 3825);
DISPLAY INVISIBLE (-4825 3825);
FORCEPROP 1 LAST BODY_TYPE PLUMBING
J 0
(-4870 3732);
DISPLAY 0.340426 (-4870 3732);
PAINT GREEN (-4870 3732);
DISPLAY INVISIBLE (-4870 3732);
FORCEPROP 1 LAST PATH I121
J 0
(-4775 3800);
DISPLAY 0.872340 (-4775 3800);
PAINT AQUA (-4775 3800);
DISPLAY INVISIBLE (-4775 3800);
FORCEPROP 2 LAST CDS_LIB mstr_symbols
J 0
(-4825 3775);
PAINT ORANGE (-4825 3775);
DISPLAY INVISIBLE (-4825 3775);
FORCEPROP 1 LAST VOLTAGE 1.05V
J 0
(-4870 3732);
DISPLAY 0.340426 (-4870 3732);
PAINT SKYBLUE (-4870 3732);
DISPLAY INVISIBLE (-4870 3732);
FORCEADD RES..2
(200 4025);
FORCEPROP 1 LAST VALUE 200.0K
J 0
(245 4100);
DISPLAY 0.617021 (245 4100);
PAINT SKYBLUE (245 4100);
FORCEPROP 1 LASTPIN (200 4125) $PN 1
J 0
(205 4087);
DISPLAY 0.617021 (205 4087);
PAINT ORANGE (205 4087);
FORCEPROP 1 LASTPIN (200 3925) $PN 2
J 0
(205 3935);
DISPLAY 0.617021 (205 3935);
PAINT ORANGE (205 3935);
FORCEPROP 1 LAST WATTAGE 1/16W
J 0
(240 4000);
DISPLAY 0.617021 (240 4000);
PAINT SKYBLUE (240 4000);
FORCEPROP 1 LAST MATERIAL CHIP
J 0
(240 3950);
DISPLAY 0.617021 (240 3950);
PAINT SKYBLUE (240 3950);
FORCEPROP 1 LAST PACK_TYPE 0402
J 0
(240 3850);
DISPLAY 0.617021 (240 3850);
PAINT SKYBLUE (240 3850);
FORCEPROP 1 LAST TOLERANCE 1%
J 0
(245 4050);
DISPLAY 0.617021 (245 4050);
PAINT SKYBLUE (245 4050);
FORCEPROP 1 LAST LOCATION R1U50
J 0
(245 4150);
DISPLAY 0.617021 (245 4150);
PAINT AQUA (245 4150);
FORCEPROP 1 LAST PART_NUMBER G21796-080
J 0
(240 3900);
DISPLAY 0.617021 (240 3900);
PAINT BLUE (240 3900);
FORCEPROP 2 LAST ROOM BMC_VOLT_MONITOR
J 0
(250 4200);
DISPLAY 1.021277 (250 4200);
PAINT ORANGE (250 4200);
DISPLAY INVISIBLE (250 4200);
FORCEPROP 1 LAST PATH I126
J 0
(250 4200);
DISPLAY 0.978723 (250 4200);
PAINT WHITE (250 4200);
DISPLAY INVISIBLE (250 4200);
FORCEPROP 2 LAST CDS_LOCATION R1U50
J 0
(245 4150);
DISPLAY 0.617021 (245 4150);
PAINT AQUA (245 4150);
DISPLAY INVISIBLE (245 4150);
FORCEPROP 2 LAST SEC 1
J 0
(250 4250);
DISPLAY 0.680851 (250 4250);
PAINT MONO (250 4250);
DISPLAY INVISIBLE (250 4250);
FORCEPROP 2 LAST BOM_COST SM_HM
J 0
(250 4250);
DISPLAY 1.021277 (250 4250);
PAINT ORANGE (250 4250);
DISPLAY INVISIBLE (250 4250);
FORCEPROP 2 LAST SEC_TYPE 0402
J 0
(250 4250);
DISPLAY 1.021277 (250 4250);
PAINT ORANGE (250 4250);
DISPLAY INVISIBLE (250 4250);
FORCEPROP 2 LAST CDS_LIB mstr_discrete
J 0
(200 4025);
PAINT ORANGE (200 4025);
DISPLAY INVISIBLE (200 4025);
FORCEADD P3V3_STBY..1
(-4825 2000);
FORCEPROP 3 LASTPIN (-4825 1950) SIG_NAME P3V3_STBY\g
J 0
(-4815 1960);
DISPLAY 0.659574 (-4815 1960);
PAINT MONO (-4815 1960);
DISPLAY INVISIBLE (-4815 1960);
FORCEPROP 1 LAST HDL_POWER P3V3_STBY
J 0
(-5125 1875);
DISPLAY 0.872340 (-5125 1875);
PAINT ORANGE (-5125 1875);
DISPLAY INVISIBLE (-5125 1875);
FORCEPROP 1 LAST BODY_TYPE PLUMBING
J 0
(-4870 1957);
DISPLAY 0.340426 (-4870 1957);
PAINT GREEN (-4870 1957);
DISPLAY INVISIBLE (-4870 1957);
FORCEPROP 1 LAST PATH I131
J 0
(-4780 2002);
DISPLAY 0.340426 (-4780 2002);
PAINT GREEN (-4780 2002);
DISPLAY INVISIBLE (-4780 2002);
FORCEPROP 2 LAST CDS_LIB mstr_symbols
J 0
(-4825 2000);
PAINT ORANGE (-4825 2000);
DISPLAY INVISIBLE (-4825 2000);
FORCEPROP 1 LAST SIZE 1B
J 0
(-4780 2022);
DISPLAY 0.340426 (-4780 2022);
PAINT GREEN (-4780 2022);
DISPLAY INVISIBLE (-4780 2022);
FORCEPROP 1 LAST VOLTAGE 3.3V
J 0
(-4870 1957);
DISPLAY 0.340426 (-4870 1957);
PAINT SKYBLUE (-4870 1957);
DISPLAY INVISIBLE (-4870 1957);
FORCEADD P12V_STBY..1
(-1125 2025);
FORCEPROP 3 LASTPIN (-1125 1975) SIG_NAME P12V_STBY\g
J 0
(-1115 1985);
DISPLAY 0.659574 (-1115 1985);
PAINT MONO (-1115 1985);
DISPLAY INVISIBLE (-1115 1985);
FORCEPROP 1 LAST HDL_POWER P12V_STBY
J 0
(-1425 1900);
DISPLAY 0.872340 (-1425 1900);
PAINT ORANGE (-1425 1900);
DISPLAY INVISIBLE (-1425 1900);
FORCEPROP 1 LAST BODY_TYPE PLUMBING
J 0
(-1170 1982);
DISPLAY 0.340426 (-1170 1982);
PAINT GREEN (-1170 1982);
DISPLAY INVISIBLE (-1170 1982);
FORCEPROP 1 LAST PATH I132
J 0
(-1080 2027);
DISPLAY 0.340426 (-1080 2027);
PAINT GREEN (-1080 2027);
DISPLAY INVISIBLE (-1080 2027);
FORCEPROP 2 LAST CDS_LIB mstr_symbols
J 0
(-1125 2025);
PAINT ORANGE (-1125 2025);
DISPLAY INVISIBLE (-1125 2025);
FORCEPROP 1 LAST SIZE 1B
J 0
(-1080 2047);
DISPLAY 0.340426 (-1080 2047);
PAINT GREEN (-1080 2047);
DISPLAY INVISIBLE (-1080 2047);
FORCEPROP 1 LAST VOLTAGE 12.0V
J 0
(-1170 1982);
DISPLAY 0.340426 (-1170 1982);
PAINT SKYBLUE (-1170 1982);
DISPLAY INVISIBLE (-1170 1982);
FORCEADD OFFPAGE..2
(-3950 4750);
FORCEPROP 2 LAST $XR0 147 
J 0
(-3761 4750);
DISPLAY 0.638298 (-3761 4750);
PAINT MONO (-3761 4750);
FORCEPROP 1 LAST COMMENT_BODY TRUE
J 0
(-3995 4655);
DISPLAY 1.170213 (-3995 4655);
PAINT GREEN (-3995 4655);
DISPLAY INVISIBLE (-3995 4655);
FORCEPROP 1 LAST OFFPAGE TRUE
J 0
(-3625 4625);
PAINT GREEN (-3625 4625);
DISPLAY INVISIBLE (-3625 4625);
FORCEPROP 2 LAST PATH I138
J 0
(-3775 4825);
DISPLAY 1.021277 (-3775 4825);
PAINT ORANGE (-3775 4825);
DISPLAY INVISIBLE (-3775 4825);
FORCEPROP 2 LAST CDS_LIB mstr_standard
J 0
(-3950 4750);
PAINT ORANGE (-3950 4750);
DISPLAY INVISIBLE (-3950 4750);
FORCEADD CAP..1
(-4350 4550);
FORCEPROP 1 LAST VOLTAGE 50V
J 0
(-4300 4550);
DISPLAY 0.617021 (-4300 4550);
PAINT SKYBLUE (-4300 4550);
FORCEPROP 1 LAST PACK_TYPE 0402LF
J 0
(-4300 4350);
DISPLAY 0.617021 (-4300 4350);
PAINT SKYBLUE (-4300 4350);
FORCEPROP 1 LASTPIN (-4350 4450) $PN 2
J 0
(-4340 4430);
DISPLAY 0.617021 (-4340 4430);
PAINT ORANGE (-4340 4430);
FORCEPROP 1 LAST MATERIAL COG
J 0
(-4300 4450);
DISPLAY 0.617021 (-4300 4450);
PAINT SKYBLUE (-4300 4450);
FORCEPROP 1 LAST TOLERANCE 5%
J 0
(-4300 4500);
DISPLAY 0.617021 (-4300 4500);
PAINT SKYBLUE (-4300 4500);
FORCEPROP 1 LAST LOCATION C9G15
J 0
(-4300 4650);
DISPLAY 0.617021 (-4300 4650);
PAINT AQUA (-4300 4650);
FORCEPROP 1 LASTPIN (-4350 4650) $PN 1
J 0
(-4340 4630);
DISPLAY 0.617021 (-4340 4630);
PAINT ORANGE (-4340 4630);
FORCEPROP 1 LAST PART_NUMBER A36095-025
J 0
(-4300 4400);
DISPLAY 0.617021 (-4300 4400);
PAINT BLUE (-4300 4400);
FORCEPROP 1 LAST VALUE 47.0PF
J 0
(-4300 4600);
DISPLAY 0.617021 (-4300 4600);
PAINT SKYBLUE (-4300 4600);
FORCEPROP 2 LAST ROOM BMC_VOLT_MONITOR
J 0
(-4300 4700);
DISPLAY 1.021277 (-4300 4700);
PAINT ORANGE (-4300 4700);
DISPLAY INVISIBLE (-4300 4700);
FORCEPROP 1 LAST PATH I139
J 0
(-4300 4700);
DISPLAY 0.978723 (-4300 4700);
PAINT WHITE (-4300 4700);
DISPLAY INVISIBLE (-4300 4700);
FORCEPROP 2 LAST CDS_LOCATION C9G15
J 0
(-4300 4650);
DISPLAY 0.617021 (-4300 4650);
PAINT AQUA (-4300 4650);
DISPLAY INVISIBLE (-4300 4650);
FORCEPROP 2 LAST SEC 1
J 0
(-4300 4750);
DISPLAY 0.680851 (-4300 4750);
PAINT MONO (-4300 4750);
DISPLAY INVISIBLE (-4300 4750);
FORCEPROP 2 LAST BOM_COST SM_HM
J 0
(-4300 4750);
DISPLAY 1.021277 (-4300 4750);
PAINT ORANGE (-4300 4750);
DISPLAY INVISIBLE (-4300 4750);
FORCEPROP 2 LAST CDS_LIB mstr_discrete
J 0
(-4350 4550);
PAINT ORANGE (-4350 4550);
DISPLAY INVISIBLE (-4350 4550);
FORCEPROP 2 LAST SEC_TYPE 0402LF
J 0
(-4300 4750);
DISPLAY 1.021277 (-4300 4750);
PAINT ORANGE (-4300 4750);
DISPLAY INVISIBLE (-4300 4750);
FORCEADD RES..2
(-4700 4950);
FORCEPROP 1 LAST PACK_TYPE 0402
J 0
(-4660 4775);
DISPLAY 0.617021 (-4660 4775);
PAINT SKYBLUE (-4660 4775);
FORCEPROP 1 LAST TOLERANCE 1%
J 0
(-4655 4975);
DISPLAY 0.617021 (-4655 4975);
PAINT SKYBLUE (-4655 4975);
FORCEPROP 1 LAST VALUE 5.11K
J 0
(-4655 5025);
DISPLAY 0.617021 (-4655 5025);
PAINT SKYBLUE (-4655 5025);
FORCEPROP 1 LASTPIN (-4700 5050) $PN 1
J 0
(-4695 5012);
DISPLAY 0.617021 (-4695 5012);
PAINT ORANGE (-4695 5012);
FORCEPROP 1 LASTPIN (-4700 4850) $PN 2
J 0
(-4695 4860);
DISPLAY 0.617021 (-4695 4860);
PAINT ORANGE (-4695 4860);
FORCEPROP 1 LAST WATTAGE 1/16W
J 0
(-4660 4925);
DISPLAY 0.617021 (-4660 4925);
PAINT SKYBLUE (-4660 4925);
FORCEPROP 1 LAST MATERIAL CHIP
J 0
(-4660 4875);
DISPLAY 0.617021 (-4660 4875);
PAINT SKYBLUE (-4660 4875);
FORCEPROP 1 LAST PART_NUMBER G21796-140
J 0
(-4660 4825);
DISPLAY 0.617021 (-4660 4825);
PAINT BLUE (-4660 4825);
FORCEPROP 1 LAST LOCATION R1U29
J 0
(-4655 5075);
DISPLAY 0.617021 (-4655 5075);
PAINT AQUA (-4655 5075);
FORCEPROP 2 LAST ROOM BMC_VOLT_MONITOR
J 0
(-4650 5125);
DISPLAY 1.021277 (-4650 5125);
PAINT ORANGE (-4650 5125);
DISPLAY INVISIBLE (-4650 5125);
FORCEPROP 1 LAST PATH I141
J 0
(-4650 5125);
DISPLAY 0.978723 (-4650 5125);
PAINT WHITE (-4650 5125);
DISPLAY INVISIBLE (-4650 5125);
FORCEPROP 2 LAST CDS_LOCATION R1U29
J 0
(-4655 5075);
DISPLAY 0.617021 (-4655 5075);
PAINT AQUA (-4655 5075);
DISPLAY INVISIBLE (-4655 5075);
FORCEPROP 2 LAST SEC 1
J 0
(-4650 5175);
DISPLAY 0.680851 (-4650 5175);
PAINT MONO (-4650 5175);
DISPLAY INVISIBLE (-4650 5175);
FORCEPROP 2 LAST SEC_TYPE 0402
J 0
(-4650 5175);
DISPLAY 1.021277 (-4650 5175);
PAINT ORANGE (-4650 5175);
DISPLAY INVISIBLE (-4650 5175);
FORCEPROP 2 LAST CDS_LIB mstr_discrete
J 0
(-4700 4950);
PAINT ORANGE (-4700 4950);
DISPLAY INVISIBLE (-4700 4950);
FORCEPROP 2 LAST BOM_COST SM_HM
J 0
(-4650 5175);
DISPLAY 1.021277 (-4650 5175);
PAINT ORANGE (-4650 5175);
DISPLAY INVISIBLE (-4650 5175);
FORCEADD GND..1
(-4700 4300);
FORCEPROP 3 LASTPIN (-4700 4350) SIG_NAME GND\g
J 0
(-4690 4360);
DISPLAY 0.659574 (-4690 4360);
PAINT MONO (-4690 4360);
DISPLAY INVISIBLE (-4690 4360);
FORCEPROP 1 LAST HDL_POWER GND
J 0
(-4700 4450);
DISPLAY 1.148936 (-4700 4450);
PAINT GREEN (-4700 4450);
DISPLAY INVISIBLE (-4700 4450);
FORCEPROP 1 LAST BODY_TYPE PLUMBING
J 0
(-4745 4257);
DISPLAY 0.340426 (-4745 4257);
PAINT GREEN (-4745 4257);
DISPLAY INVISIBLE (-4745 4257);
FORCEPROP 1 LAST PATH I143
J 0
(-4625 4300);
DISPLAY 0.872340 (-4625 4300);
PAINT AQUA (-4625 4300);
DISPLAY INVISIBLE (-4625 4300);
FORCEPROP 2 LAST CDS_LIB mstr_symbols
J 0
(-4700 4300);
PAINT ORANGE (-4700 4300);
DISPLAY INVISIBLE (-4700 4300);
FORCEPROP 1 LAST SIZE 1B
J 0
(-4625 4250);
DISPLAY 1.148936 (-4625 4250);
PAINT GREEN (-4625 4250);
DISPLAY INVISIBLE (-4625 4250);
FORCEPROP 1 LAST VOLTAGE 0
J 0
(-4700 4300);
PAINT SKYBLUE (-4700 4300);
DISPLAY INVISIBLE (-4700 4300);
FORCEADD P5V..1
(-4700 5175);
FORCEPROP 3 LASTPIN (-4700 5125) SIG_NAME P5V\g
J 0
(-4690 5135);
DISPLAY 0.659574 (-4690 5135);
PAINT MONO (-4690 5135);
DISPLAY INVISIBLE (-4690 5135);
FORCEPROP 1 LAST HDL_POWER P5V
J 0
(-5000 5050);
DISPLAY 0.872340 (-5000 5050);
PAINT ORANGE (-5000 5050);
DISPLAY INVISIBLE (-5000 5050);
FORCEPROP 1 LAST BODY_TYPE PLUMBING
J 0
(-4745 5132);
DISPLAY 0.340426 (-4745 5132);
PAINT GREEN (-4745 5132);
DISPLAY INVISIBLE (-4745 5132);
FORCEPROP 1 LAST PATH I144
J 0
(-4655 5177);
DISPLAY 0.340426 (-4655 5177);
PAINT GREEN (-4655 5177);
DISPLAY INVISIBLE (-4655 5177);
FORCEPROP 2 LAST CDS_LIB mstr_symbols
J 0
(-4700 5175);
PAINT ORANGE (-4700 5175);
DISPLAY INVISIBLE (-4700 5175);
FORCEPROP 1 LAST SIZE 1B
J 0
(-4655 5197);
DISPLAY 0.340426 (-4655 5197);
PAINT GREEN (-4655 5197);
DISPLAY INVISIBLE (-4655 5197);
FORCEPROP 1 LAST VOLTAGE 5.0V
J 0
(-4745 5132);
DISPLAY 0.340426 (-4745 5132);
PAINT SKYBLUE (-4745 5132);
DISPLAY INVISIBLE (-4745 5132);
FORCEADD OFFPAGE..2
(-2050 4800);
FORCEPROP 2 LAST $XR0 147 
J 0
(-1861 4800);
DISPLAY 0.638298 (-1861 4800);
PAINT MONO (-1861 4800);
FORCEPROP 1 LAST COMMENT_BODY TRUE
J 0
(-2095 4705);
DISPLAY 1.170213 (-2095 4705);
PAINT GREEN (-2095 4705);
DISPLAY INVISIBLE (-2095 4705);
FORCEPROP 1 LAST OFFPAGE TRUE
J 0
(-1725 4675);
PAINT GREEN (-1725 4675);
DISPLAY INVISIBLE (-1725 4675);
FORCEPROP 2 LAST PATH I145
J 0
(-1875 4875);
DISPLAY 1.021277 (-1875 4875);
PAINT ORANGE (-1875 4875);
DISPLAY INVISIBLE (-1875 4875);
FORCEPROP 2 LAST CDS_LIB mstr_standard
J 0
(-2050 4800);
PAINT ORANGE (-2050 4800);
DISPLAY INVISIBLE (-2050 4800);
FORCEADD CAP..1
(-2550 4600);
FORCEPROP 1 LAST PART_NUMBER A36095-025
J 0
(-2500 4450);
DISPLAY 0.617021 (-2500 4450);
PAINT BLUE (-2500 4450);
FORCEPROP 1 LAST LOCATION C9G14
J 0
(-2500 4700);
DISPLAY 0.617021 (-2500 4700);
PAINT AQUA (-2500 4700);
FORCEPROP 1 LAST VALUE 47.0PF
J 0
(-2500 4650);
DISPLAY 0.617021 (-2500 4650);
PAINT SKYBLUE (-2500 4650);
FORCEPROP 1 LAST MATERIAL COG
J 0
(-2500 4500);
DISPLAY 0.617021 (-2500 4500);
PAINT SKYBLUE (-2500 4500);
FORCEPROP 1 LAST TOLERANCE 5%
J 0
(-2500 4550);
DISPLAY 0.617021 (-2500 4550);
PAINT SKYBLUE (-2500 4550);
FORCEPROP 1 LAST VOLTAGE 50V
J 0
(-2500 4600);
DISPLAY 0.617021 (-2500 4600);
PAINT SKYBLUE (-2500 4600);
FORCEPROP 1 LASTPIN (-2550 4700) $PN 1
J 0
(-2540 4680);
DISPLAY 0.617021 (-2540 4680);
PAINT ORANGE (-2540 4680);
FORCEPROP 1 LASTPIN (-2550 4500) $PN 2
J 0
(-2540 4480);
DISPLAY 0.617021 (-2540 4480);
PAINT ORANGE (-2540 4480);
FORCEPROP 1 LAST PACK_TYPE 0402LF
J 0
(-2500 4400);
DISPLAY 0.617021 (-2500 4400);
PAINT SKYBLUE (-2500 4400);
FORCEPROP 2 LAST ROOM BMC_VOLT_MONITOR
J 0
(-2500 4750);
DISPLAY 1.021277 (-2500 4750);
PAINT ORANGE (-2500 4750);
DISPLAY INVISIBLE (-2500 4750);
FORCEPROP 1 LAST PATH I146
J 0
(-2500 4750);
DISPLAY 0.978723 (-2500 4750);
PAINT WHITE (-2500 4750);
DISPLAY INVISIBLE (-2500 4750);
FORCEPROP 2 LAST CDS_LOCATION C9G14
J 0
(-2500 4700);
DISPLAY 0.617021 (-2500 4700);
PAINT AQUA (-2500 4700);
DISPLAY INVISIBLE (-2500 4700);
FORCEPROP 2 LAST SEC 1
J 0
(-2500 4800);
DISPLAY 0.680851 (-2500 4800);
PAINT MONO (-2500 4800);
DISPLAY INVISIBLE (-2500 4800);
FORCEPROP 2 LAST BOM_COST SM_HM
J 0
(-2500 4800);
DISPLAY 1.021277 (-2500 4800);
PAINT ORANGE (-2500 4800);
DISPLAY INVISIBLE (-2500 4800);
FORCEPROP 2 LAST CDS_LIB mstr_discrete
J 0
(-2550 4600);
PAINT ORANGE (-2550 4600);
DISPLAY INVISIBLE (-2550 4600);
FORCEPROP 2 LAST SEC_TYPE 0402LF
J 0
(-2500 4800);
DISPLAY 1.021277 (-2500 4800);
PAINT ORANGE (-2500 4800);
DISPLAY INVISIBLE (-2500 4800);
FORCEADD RES..2
(-2900 5000);
FORCEPROP 1 LAST WATTAGE 1/16W
J 0
(-2860 4975);
DISPLAY 0.617021 (-2860 4975);
PAINT SKYBLUE (-2860 4975);
FORCEPROP 1 LAST PART_NUMBER G21796-140
J 0
(-2860 4875);
DISPLAY 0.617021 (-2860 4875);
PAINT BLUE (-2860 4875);
FORCEPROP 1 LASTPIN (-2900 4900) $PN 2
J 0
(-2895 4910);
DISPLAY 0.617021 (-2895 4910);
PAINT ORANGE (-2895 4910);
FORCEPROP 1 LAST MATERIAL CHIP
J 0
(-2860 4925);
DISPLAY 0.617021 (-2860 4925);
PAINT SKYBLUE (-2860 4925);
FORCEPROP 1 LAST PACK_TYPE 0402
J 0
(-2860 4825);
DISPLAY 0.617021 (-2860 4825);
PAINT SKYBLUE (-2860 4825);
FORCEPROP 1 LAST LOCATION R1U26
J 0
(-2855 5125);
DISPLAY 0.617021 (-2855 5125);
PAINT AQUA (-2855 5125);
FORCEPROP 1 LAST VALUE 5.11K
J 0
(-2855 5075);
DISPLAY 0.617021 (-2855 5075);
PAINT SKYBLUE (-2855 5075);
FORCEPROP 1 LAST TOLERANCE 1%
J 0
(-2855 5025);
DISPLAY 0.617021 (-2855 5025);
PAINT SKYBLUE (-2855 5025);
FORCEPROP 1 LASTPIN (-2900 5100) $PN 1
J 0
(-2895 5062);
DISPLAY 0.617021 (-2895 5062);
PAINT ORANGE (-2895 5062);
FORCEPROP 2 LAST ROOM BMC_VOLT_MONITOR
J 0
(-2850 5175);
DISPLAY 1.021277 (-2850 5175);
PAINT ORANGE (-2850 5175);
DISPLAY INVISIBLE (-2850 5175);
FORCEPROP 1 LAST PATH I148
J 0
(-2850 5175);
DISPLAY 0.978723 (-2850 5175);
PAINT WHITE (-2850 5175);
DISPLAY INVISIBLE (-2850 5175);
FORCEPROP 2 LAST CDS_LOCATION R1U26
J 0
(-2855 5125);
DISPLAY 0.617021 (-2855 5125);
PAINT AQUA (-2855 5125);
DISPLAY INVISIBLE (-2855 5125);
FORCEPROP 2 LAST SEC 1
J 0
(-2850 5225);
DISPLAY 0.680851 (-2850 5225);
PAINT MONO (-2850 5225);
DISPLAY INVISIBLE (-2850 5225);
FORCEPROP 2 LAST SEC_TYPE 0402
J 0
(-2850 5225);
DISPLAY 1.021277 (-2850 5225);
PAINT ORANGE (-2850 5225);
DISPLAY INVISIBLE (-2850 5225);
FORCEPROP 2 LAST CDS_LIB mstr_discrete
J 0
(-2900 5000);
PAINT ORANGE (-2900 5000);
DISPLAY INVISIBLE (-2900 5000);
FORCEPROP 2 LAST BOM_COST SM_HM
J 0
(-2850 5225);
DISPLAY 1.021277 (-2850 5225);
PAINT ORANGE (-2850 5225);
DISPLAY INVISIBLE (-2850 5225);
FORCEADD GND..1
(-2900 4350);
FORCEPROP 3 LASTPIN (-2900 4400) SIG_NAME GND\g
J 0
(-2890 4410);
DISPLAY 0.659574 (-2890 4410);
PAINT MONO (-2890 4410);
DISPLAY INVISIBLE (-2890 4410);
FORCEPROP 1 LAST HDL_POWER GND
J 0
(-2900 4500);
DISPLAY 1.148936 (-2900 4500);
PAINT GREEN (-2900 4500);
DISPLAY INVISIBLE (-2900 4500);
FORCEPROP 1 LAST BODY_TYPE PLUMBING
J 0
(-2945 4307);
DISPLAY 0.340426 (-2945 4307);
PAINT GREEN (-2945 4307);
DISPLAY INVISIBLE (-2945 4307);
FORCEPROP 1 LAST PATH I150
J 0
(-2825 4350);
DISPLAY 0.872340 (-2825 4350);
PAINT AQUA (-2825 4350);
DISPLAY INVISIBLE (-2825 4350);
FORCEPROP 2 LAST CDS_LIB mstr_symbols
J 0
(-2900 4350);
PAINT ORANGE (-2900 4350);
DISPLAY INVISIBLE (-2900 4350);
FORCEPROP 1 LAST SIZE 1B
J 0
(-2825 4300);
DISPLAY 1.148936 (-2825 4300);
PAINT GREEN (-2825 4300);
DISPLAY INVISIBLE (-2825 4300);
FORCEPROP 1 LAST VOLTAGE 0
J 0
(-2900 4350);
PAINT SKYBLUE (-2900 4350);
DISPLAY INVISIBLE (-2900 4350);
FORCEADD P3V3..1
(-2900 5200);
FORCEPROP 3 LASTPIN (-2900 5150) SIG_NAME P3V3\g
J 0
(-2890 5160);
DISPLAY 0.659574 (-2890 5160);
PAINT MONO (-2890 5160);
DISPLAY INVISIBLE (-2890 5160);
FORCEPROP 1 LAST HDL_POWER P3V3
J 0
(-3225 5075);
DISPLAY 0.872340 (-3225 5075);
PAINT ORANGE (-3225 5075);
DISPLAY INVISIBLE (-3225 5075);
FORCEPROP 1 LAST BODY_TYPE PLUMBING
J 0
(-2945 5157);
DISPLAY 0.340426 (-2945 5157);
PAINT GREEN (-2945 5157);
DISPLAY INVISIBLE (-2945 5157);
FORCEPROP 1 LAST PATH I151
J 0
(-2855 5202);
DISPLAY 0.340426 (-2855 5202);
PAINT GREEN (-2855 5202);
DISPLAY INVISIBLE (-2855 5202);
FORCEPROP 2 LAST CDS_LIB mstr_symbols
J 0
(-2900 5200);
PAINT ORANGE (-2900 5200);
DISPLAY INVISIBLE (-2900 5200);
FORCEPROP 1 LAST SIZE 1B
J 0
(-2855 5222);
DISPLAY 0.340426 (-2855 5222);
PAINT GREEN (-2855 5222);
DISPLAY INVISIBLE (-2855 5222);
FORCEPROP 1 LAST VOLTAGE 3.3V
J 0
(-2945 5157);
DISPLAY 0.340426 (-2945 5157);
PAINT SKYBLUE (-2945 5157);
DISPLAY INVISIBLE (-2945 5157);
FORCEADD OFFPAGE..2
(1650 1650);
FORCEPROP 2 LAST $XR0 147 
J 0
(1839 1650);
DISPLAY 0.638298 (1839 1650);
PAINT MONO (1839 1650);
FORCEPROP 1 LAST COMMENT_BODY TRUE
J 0
(1605 1555);
DISPLAY 1.170213 (1605 1555);
PAINT GREEN (1605 1555);
DISPLAY INVISIBLE (1605 1555);
FORCEPROP 1 LAST OFFPAGE TRUE
J 0
(1975 1525);
PAINT GREEN (1975 1525);
DISPLAY INVISIBLE (1975 1525);
FORCEPROP 2 LAST PATH I152
J 0
(1850 1700);
DISPLAY 1.021277 (1850 1700);
PAINT ORANGE (1850 1700);
DISPLAY INVISIBLE (1850 1700);
FORCEPROP 2 LAST CDS_LIB mstr_standard
J 0
(1650 1650);
DISPLAY 1.361702 (1650 1650);
PAINT ORANGE (1650 1650);
DISPLAY INVISIBLE (1650 1650);
FORCEADD CAP..1
(800 1475);
FORCEPROP 1 LAST PART_NUMBER A36095-025
J 0
(850 1325);
DISPLAY 0.617021 (850 1325);
PAINT BLUE (850 1325);
FORCEPROP 1 LAST MATERIAL COG
J 0
(850 1375);
DISPLAY 0.617021 (850 1375);
PAINT SKYBLUE (850 1375);
FORCEPROP 1 LAST VALUE 47.0PF
J 0
(850 1525);
DISPLAY 0.617021 (850 1525);
PAINT SKYBLUE (850 1525);
FORCEPROP 1 LASTPIN (800 1575) $PN 1
J 0
(810 1555);
DISPLAY 0.617021 (810 1555);
PAINT MONO (810 1555);
FORCEPROP 1 LASTPIN (800 1375) $PN 2
J 0
(810 1355);
DISPLAY 0.617021 (810 1355);
PAINT MONO (810 1355);
FORCEPROP 1 LAST VOLTAGE 50V
J 0
(850 1475);
DISPLAY 0.617021 (850 1475);
PAINT SKYBLUE (850 1475);
FORCEPROP 1 LAST PACK_TYPE 0402LF
J 0
(850 1275);
DISPLAY 0.617021 (850 1275);
PAINT SKYBLUE (850 1275);
FORCEPROP 1 LAST TOLERANCE 5%
J 0
(850 1425);
DISPLAY 0.617021 (850 1425);
PAINT SKYBLUE (850 1425);
FORCEPROP 1 LAST LOCATION C9G18
J 0
(850 1575);
DISPLAY 0.617021 (850 1575);
PAINT AQUA (850 1575);
FORCEPROP 2 LAST ROOM BMC_VOLT_MONITOR
J 0
(850 1625);
DISPLAY 1.021277 (850 1625);
PAINT ORANGE (850 1625);
DISPLAY INVISIBLE (850 1625);
FORCEPROP 1 LAST PATH I153
J 0
(850 1625);
DISPLAY 0.978723 (850 1625);
PAINT WHITE (850 1625);
DISPLAY INVISIBLE (850 1625);
FORCEPROP 2 LAST CDS_LOCATION C9G18
J 0
(850 1575);
DISPLAY 0.617021 (850 1575);
PAINT AQUA (850 1575);
DISPLAY INVISIBLE (850 1575);
FORCEPROP 2 LAST SEC 1
J 0
(850 1675);
DISPLAY 0.936170 (850 1675);
PAINT MONO (850 1675);
DISPLAY INVISIBLE (850 1675);
FORCEPROP 2 LAST BOM_COST SM_HM
J 0
(850 1675);
DISPLAY 1.021277 (850 1675);
PAINT ORANGE (850 1675);
DISPLAY INVISIBLE (850 1675);
FORCEPROP 2 LAST CDS_LIB mstr_discrete
J 0
(800 1475);
DISPLAY 1.361702 (800 1475);
PAINT ORANGE (800 1475);
DISPLAY INVISIBLE (800 1475);
FORCEPROP 2 LAST SEC_TYPE 0402LF
J 0
(850 1675);
PAINT MONO (850 1675);
DISPLAY INVISIBLE (850 1675);
FORCEADD PVNN_PCH_STBY..1
(800 2025);
FORCEPROP 3 LASTPIN (800 1975) SIG_NAME PVNN_PCH_STBY\g
J 0
(810 1985);
DISPLAY 0.659574 (810 1985);
PAINT MONO (810 1985);
DISPLAY INVISIBLE (810 1985);
FORCEPROP 1 LAST HDL_POWER PVNN_PCH_STBY
J 1
(800 2075);
DISPLAY 0.872340 (800 2075);
PAINT GREEN (800 2075);
DISPLAY INVISIBLE (800 2075);
FORCEPROP 1 LAST BODY_TYPE PLUMBING
J 0
(755 1982);
DISPLAY 0.340426 (755 1982);
PAINT GREEN (755 1982);
DISPLAY INVISIBLE (755 1982);
FORCEPROP 1 LAST PATH I154
J 0
(850 2050);
DISPLAY 0.872340 (850 2050);
PAINT AQUA (850 2050);
DISPLAY INVISIBLE (850 2050);
FORCEPROP 2 LAST CDS_LIB mstr_symbols
J 0
(800 2025);
PAINT ORANGE (800 2025);
DISPLAY INVISIBLE (800 2025);
FORCEPROP 1 LAST VOLTAGE 1.0V
J 0
(755 1982);
DISPLAY 0.340426 (755 1982);
PAINT SKYBLUE (755 1982);
DISPLAY INVISIBLE (755 1982);
FORCEADD FERRITE..4
(800 1850);
FORCEPROP 1 LAST MATERIAL FB
J 0
(861 1695);
DISPLAY 0.617021 (861 1695);
PAINT SKYBLUE (861 1695);
FORCEPROP 1 LASTPIN (800 1950) $PN 2
J 0
(820 1920);
DISPLAY 0.617021 (820 1920);
PAINT MONO (820 1920);
FORCEPROP 1 LAST LOCATION FB1U4
J 0
(860 1895);
DISPLAY 0.617021 (860 1895);
PAINT AQUA (860 1895);
FORCEPROP 1 LAST PART_NUMBER 693286-021
J 0
(860 1795);
DISPLAY 0.617021 (860 1795);
PAINT BLUE (860 1795);
FORCEPROP 1 LASTPIN (800 1750) $PN 1
J 0
(820 1750);
DISPLAY 0.617021 (820 1750);
PAINT MONO (820 1750);
FORCEPROP 1 LAST PACK_TYPE SMLF
J 0
(860 1745);
DISPLAY 0.617021 (860 1745);
PAINT SKYBLUE (860 1745);
FORCEPROP 1 LAST VALUE 30
J 0
(860 1845);
DISPLAY 0.617021 (860 1845);
PAINT SKYBLUE (860 1845);
FORCEPROP 2 LAST ROOM BMC_VOLT_MONITOR
J 0
(875 1925);
DISPLAY 1.021277 (875 1925);
PAINT ORANGE (875 1925);
DISPLAY INVISIBLE (875 1925);
FORCEPROP 1 LAST PATH I155
J 0
(865 1945);
DISPLAY 0.978723 (865 1945);
PAINT WHITE (865 1945);
DISPLAY INVISIBLE (865 1945);
FORCEPROP 2 LAST CDS_LOCATION FB1U4
J 0
(860 1895);
DISPLAY 0.617021 (860 1895);
PAINT AQUA (860 1895);
DISPLAY INVISIBLE (860 1895);
FORCEPROP 2 LAST SEC 1
J 0
(875 2000);
DISPLAY 0.936170 (875 2000);
PAINT MONO (875 2000);
DISPLAY INVISIBLE (875 2000);
FORCEPROP 2 LAST BOM_COST SM_HM
J 0
(875 1975);
DISPLAY 1.021277 (875 1975);
PAINT ORANGE (875 1975);
DISPLAY INVISIBLE (875 1975);
FORCEPROP 2 LAST SEC_TYPE SMLF
J 0
(875 2000);
PAINT MONO (875 2000);
DISPLAY INVISIBLE (875 2000);
FORCEPROP 2 LAST CDS_LIB mstr_discrete
J 0
(800 1850);
DISPLAY 1.361702 (800 1850);
PAINT ORANGE (800 1850);
DISPLAY INVISIBLE (800 1850);
FORCEADD GND..1
(800 1250);
FORCEPROP 3 LASTPIN (800 1300) SIG_NAME GND\g
J 0
(810 1310);
DISPLAY 0.659574 (810 1310);
PAINT MONO (810 1310);
DISPLAY INVISIBLE (810 1310);
FORCEPROP 1 LAST HDL_POWER GND
J 0
(800 1400);
DISPLAY 1.148936 (800 1400);
PAINT GREEN (800 1400);
DISPLAY INVISIBLE (800 1400);
FORCEPROP 1 LAST BODY_TYPE PLUMBING
J 0
(755 1207);
DISPLAY 0.340426 (755 1207);
PAINT GREEN (755 1207);
DISPLAY INVISIBLE (755 1207);
FORCEPROP 1 LAST PATH I156
J 0
(875 1250);
DISPLAY 0.872340 (875 1250);
PAINT AQUA (875 1250);
DISPLAY INVISIBLE (875 1250);
FORCEPROP 1 LAST SIZE 1B
J 0
(875 1200);
DISPLAY 1.148936 (875 1200);
PAINT GREEN (875 1200);
DISPLAY INVISIBLE (875 1200);
FORCEPROP 2 LAST CDS_LIB mstr_symbols
J 0
(800 1250);
DISPLAY 1.361702 (800 1250);
PAINT ORANGE (800 1250);
DISPLAY INVISIBLE (800 1250);
FORCEPROP 1 LAST VOLTAGE 0
J 0
(800 1250);
PAINT SKYBLUE (800 1250);
DISPLAY INVISIBLE (800 1250);
FORCEADD FET_N_DUAL..5
(200 3225);
FORCEPROP 1 LASTPIN (200 3425) $PN 3
J 2
(253 3390);
DISPLAY 0.617021 (253 3390);
PAINT WHITE (253 3390);
FORCEPROP 1 LAST VALUE NTJD4001N
J 0
(400 3175);
DISPLAY 0.617021 (400 3175);
PAINT SKYBLUE (400 3175);
FORCEPROP 1 LASTPIN (0 3125) $PN 5
J 2
(3 3140);
DISPLAY 0.617021 (3 3140);
PAINT WHITE (3 3140);
FORCEPROP 1 LASTPIN (200 3025) $PN 4
J 2
(258 3025);
DISPLAY 0.617021 (258 3025);
PAINT WHITE (258 3025);
FORCEPROP 1 LAST MATERIAL FET
J 0
(400 3125);
DISPLAY 0.617021 (400 3125);
PAINT SKYBLUE (400 3125);
FORCEPROP 1 LAST LOCATION Q9G1
J 0
(400 3225);
DISPLAY 0.617021 (400 3225);
PAINT AQUA (400 3225);
FORCEPROP 1 LAST PART_NUMBER E40049-001
J 0
(400 3025);
DISPLAY 0.617021 (400 3025);
PAINT BLUE (400 3025);
FORCEPROP 0 LAST ROOM BMC_VOLT_MONITOR
J 0
(400 3325);
DISPLAY 1.021277 (400 3325);
PAINT ORANGE (400 3325);
DISPLAY INVISIBLE (400 3325);
FORCEPROP 1 LAST PATH I157
J 0
(400 3275);
DISPLAY 0.978723 (400 3275);
PAINT BLUE (400 3275);
DISPLAY INVISIBLE (400 3275);
FORCEPROP 2 LAST CDS_LOCATION Q9G1
J 0
(400 3225);
DISPLAY 0.617021 (400 3225);
PAINT AQUA (400 3225);
DISPLAY INVISIBLE (400 3225);
FORCEPROP 2 LAST SEC 2
J 0
(400 3325);
DISPLAY 0.680851 (400 3325);
PAINT MONO (400 3325);
DISPLAY INVISIBLE (400 3325);
FORCEPROP 2 LAST CDS_LIB mstr_discrete
J 0
(200 3225);
PAINT ORANGE (200 3225);
DISPLAY INVISIBLE (200 3225);
FORCEPROP 0 LAST BOM_COST SM_HM
J 0
(400 3425);
DISPLAY 1.021277 (400 3425);
PAINT ORANGE (400 3425);
DISPLAY INVISIBLE (400 3425);
FORCEPROP 2 LAST SEC_TYPE SMLF
J 0
(400 3325);
DISPLAY 1.021277 (400 3325);
PAINT ORANGE (400 3325);
DISPLAY INVISIBLE (400 3325);
FORCEPROP 1 LAST PACK_TYPE SMLF
J 0
(400 3075);
DISPLAY 0.978723 (400 3075);
PAINT SKYBLUE (400 3075);
DISPLAY INVISIBLE (400 3075);
FORCEADD GND..1
(-875 2525);
FORCEPROP 3 LASTPIN (-875 2575) SIG_NAME GND\g
J 0
(-865 2585);
DISPLAY 0.659574 (-865 2585);
PAINT MONO (-865 2585);
DISPLAY INVISIBLE (-865 2585);
FORCEPROP 1 LAST HDL_POWER GND
J 0
(-875 2675);
DISPLAY 1.148936 (-875 2675);
PAINT GREEN (-875 2675);
DISPLAY INVISIBLE (-875 2675);
FORCEPROP 1 LAST BODY_TYPE PLUMBING
J 0
(-920 2482);
DISPLAY 0.340426 (-920 2482);
PAINT GREEN (-920 2482);
DISPLAY INVISIBLE (-920 2482);
FORCEPROP 1 LAST PATH I160
J 0
(-800 2525);
DISPLAY 0.872340 (-800 2525);
PAINT AQUA (-800 2525);
DISPLAY INVISIBLE (-800 2525);
FORCEPROP 2 LAST CDS_LIB mstr_symbols
J 0
(-875 2525);
PAINT ORANGE (-875 2525);
DISPLAY INVISIBLE (-875 2525);
FORCEPROP 1 LAST SIZE 1B
J 0
(-800 2475);
DISPLAY 1.148936 (-800 2475);
PAINT GREEN (-800 2475);
DISPLAY INVISIBLE (-800 2475);
FORCEPROP 1 LAST VOLTAGE 0
J 0
(-875 2525);
PAINT SKYBLUE (-875 2525);
DISPLAY INVISIBLE (-875 2525);
FORCEADD OFFPAGE..1
(-2100 2800);
FORCEPROP 2 LAST $XR1 145 
J 0
(-2472 2800);
DISPLAY 0.638298 (-2472 2800);
PAINT MONO (-2472 2800);
FORCEPROP 2 LAST $XR0 118 
J 0
(-2352 2800);
DISPLAY 0.638298 (-2352 2800);
PAINT MONO (-2352 2800);
FORCEPROP 1 LAST COMMENT_BODY TRUE
J 0
(-1975 2700);
DISPLAY 0.872340 (-1975 2700);
PAINT GREEN (-1975 2700);
DISPLAY INVISIBLE (-1975 2700);
FORCEPROP 1 LAST OFFPAGE TRUE
J 0
(-1775 2675);
DISPLAY 0.872340 (-1775 2675);
PAINT GREEN (-1775 2675);
DISPLAY INVISIBLE (-1775 2675);
FORCEPROP 2 LAST PATH I161
J 0
(-2350 2850);
DISPLAY 1.021277 (-2350 2850);
PAINT ORANGE (-2350 2850);
DISPLAY INVISIBLE (-2350 2850);
FORCEPROP 2 LAST CDS_LIB mstr_standard
J 0
(-2100 2800);
PAINT ORANGE (-2100 2800);
DISPLAY INVISIBLE (-2100 2800);
FORCEADD FET_N_DUAL..5
(-875 2900);
FORCEPROP 1 LAST VALUE NTJD4001N
J 0
(-675 2850);
DISPLAY 0.617021 (-675 2850);
PAINT SKYBLUE (-675 2850);
FORCEPROP 1 LAST MATERIAL FET
J 0
(-675 2800);
DISPLAY 0.617021 (-675 2800);
PAINT SKYBLUE (-675 2800);
FORCEPROP 1 LAST PART_NUMBER E40049-001
J 0
(-675 2700);
DISPLAY 0.617021 (-675 2700);
PAINT BLUE (-675 2700);
FORCEPROP 1 LASTPIN (-875 3100) $PN 6
J 2
(-822 3065);
DISPLAY 0.617021 (-822 3065);
PAINT WHITE (-822 3065);
FORCEPROP 1 LASTPIN (-1075 2800) $PN 2
J 2
(-1072 2815);
DISPLAY 0.617021 (-1072 2815);
PAINT WHITE (-1072 2815);
FORCEPROP 1 LASTPIN (-875 2700) $PN 1
J 2
(-817 2700);
DISPLAY 0.617021 (-817 2700);
PAINT WHITE (-817 2700);
FORCEPROP 1 LAST LOCATION Q9G1
J 0
(-675 2900);
DISPLAY 0.617021 (-675 2900);
PAINT AQUA (-675 2900);
FORCEPROP 0 LAST ROOM BMC_VOLT_MONITOR
J 0
(-675 3000);
DISPLAY 1.021277 (-675 3000);
PAINT ORANGE (-675 3000);
DISPLAY INVISIBLE (-675 3000);
FORCEPROP 1 LAST PATH I162
J 0
(-675 2950);
DISPLAY 0.978723 (-675 2950);
PAINT BLUE (-675 2950);
DISPLAY INVISIBLE (-675 2950);
FORCEPROP 2 LAST CDS_LOCATION Q9G1
J 0
(-675 2900);
DISPLAY 0.617021 (-675 2900);
PAINT AQUA (-675 2900);
DISPLAY INVISIBLE (-675 2900);
FORCEPROP 2 LAST SEC 1
J 0
(-675 3000);
DISPLAY 0.680851 (-675 3000);
PAINT MONO (-675 3000);
DISPLAY INVISIBLE (-675 3000);
FORCEPROP 2 LAST SEC_TYPE SMLF
J 0
(-675 3000);
DISPLAY 1.021277 (-675 3000);
PAINT ORANGE (-675 3000);
DISPLAY INVISIBLE (-675 3000);
FORCEPROP 0 LAST BOM_COST SM_HM
J 0
(-675 3100);
DISPLAY 1.021277 (-675 3100);
PAINT ORANGE (-675 3100);
DISPLAY INVISIBLE (-675 3100);
FORCEPROP 2 LAST CDS_LIB mstr_discrete
J 0
(-875 2900);
PAINT ORANGE (-875 2900);
DISPLAY INVISIBLE (-875 2900);
FORCEPROP 1 LAST PACK_TYPE SMLF
J 0
(-675 2750);
DISPLAY 0.978723 (-675 2750);
PAINT SKYBLUE (-675 2750);
DISPLAY INVISIBLE (-675 2750);
FORCEADD RES..2
(-650 3375);
FORCEPROP 1 LAST LOCATION R1U49
J 0
(-605 3500);
DISPLAY 0.617021 (-605 3500);
PAINT AQUA (-605 3500);
FORCEPROP 1 LASTPIN (-650 3475) $PN 1
J 0
(-645 3437);
DISPLAY 0.617021 (-645 3437);
PAINT ORANGE (-645 3437);
FORCEPROP 1 LASTPIN (-650 3275) $PN 2
J 0
(-645 3285);
DISPLAY 0.617021 (-645 3285);
PAINT ORANGE (-645 3285);
FORCEPROP 1 LAST WATTAGE 1/16W
J 0
(-610 3350);
DISPLAY 0.617021 (-610 3350);
PAINT SKYBLUE (-610 3350);
FORCEPROP 1 LAST MATERIAL CHIP
J 0
(-610 3300);
DISPLAY 0.617021 (-610 3300);
PAINT SKYBLUE (-610 3300);
FORCEPROP 1 LAST PACK_TYPE 0402
J 0
(-610 3200);
DISPLAY 0.617021 (-610 3200);
PAINT SKYBLUE (-610 3200);
FORCEPROP 1 LAST TOLERANCE 1%
J 0
(-605 3400);
DISPLAY 0.617021 (-605 3400);
PAINT SKYBLUE (-605 3400);
FORCEPROP 1 LAST VALUE 2.7K
J 0
(-605 3450);
DISPLAY 0.617021 (-605 3450);
PAINT SKYBLUE (-605 3450);
FORCEPROP 1 LAST PART_NUMBER G21796-344
J 0
(-610 3250);
DISPLAY 0.617021 (-610 3250);
PAINT BLUE (-610 3250);
FORCEPROP 2 LAST ROOM BMC_VOLT_MONITOR
J 0
(-600 3550);
DISPLAY 1.021277 (-600 3550);
PAINT ORANGE (-600 3550);
DISPLAY INVISIBLE (-600 3550);
FORCEPROP 1 LAST PATH I163
J 0
(-600 3550);
DISPLAY 0.978723 (-600 3550);
PAINT WHITE (-600 3550);
DISPLAY INVISIBLE (-600 3550);
FORCEPROP 2 LAST CDS_LOCATION R1U49
J 0
(-605 3500);
DISPLAY 0.617021 (-605 3500);
PAINT AQUA (-605 3500);
DISPLAY INVISIBLE (-605 3500);
FORCEPROP 2 LAST SEC 1
J 0
(-600 3600);
DISPLAY 0.680851 (-600 3600);
PAINT MONO (-600 3600);
DISPLAY INVISIBLE (-600 3600);
FORCEPROP 2 LAST CDS_LIB mstr_discrete
J 0
(-650 3375);
PAINT ORANGE (-650 3375);
DISPLAY INVISIBLE (-650 3375);
FORCEPROP 2 LAST BOM_COST SM_HM
J 0
(-600 3600);
DISPLAY 1.021277 (-600 3600);
PAINT ORANGE (-600 3600);
DISPLAY INVISIBLE (-600 3600);
FORCEPROP 2 LAST SEC_TYPE 0402
J 0
(-600 3600);
DISPLAY 1.021277 (-600 3600);
PAINT ORANGE (-600 3600);
DISPLAY INVISIBLE (-600 3600);
FORCEADD RES..2
(-1400 3025);
FORCEPROP 1 LAST PART_NUMBER G21796-344
J 0
(-1360 2900);
DISPLAY 0.617021 (-1360 2900);
PAINT BLUE (-1360 2900);
FORCEPROP 1 LAST TOLERANCE 1%
J 0
(-1355 3050);
DISPLAY 0.617021 (-1355 3050);
PAINT SKYBLUE (-1355 3050);
FORCEPROP 1 LAST MATERIAL CHIP
J 0
(-1360 2950);
DISPLAY 0.617021 (-1360 2950);
PAINT SKYBLUE (-1360 2950);
FORCEPROP 1 LAST WATTAGE 1/16W
J 0
(-1360 3000);
DISPLAY 0.617021 (-1360 3000);
PAINT SKYBLUE (-1360 3000);
FORCEPROP 1 LASTPIN (-1400 2925) $PN 2
J 0
(-1395 2935);
DISPLAY 0.617021 (-1395 2935);
PAINT ORANGE (-1395 2935);
FORCEPROP 1 LASTPIN (-1400 3125) $PN 1
J 0
(-1395 3087);
DISPLAY 0.617021 (-1395 3087);
PAINT ORANGE (-1395 3087);
FORCEPROP 1 LAST VALUE 2.7K
J 0
(-1355 3100);
DISPLAY 0.617021 (-1355 3100);
PAINT SKYBLUE (-1355 3100);
FORCEPROP 1 LAST LOCATION R9G35
J 0
(-1355 3150);
DISPLAY 0.617021 (-1355 3150);
PAINT AQUA (-1355 3150);
FORCEPROP 1 LAST PACK_TYPE 0402
J 0
(-1360 2850);
DISPLAY 0.617021 (-1360 2850);
PAINT SKYBLUE (-1360 2850);
FORCEPROP 2 LAST CDS_LIB mstr_discrete
J 0
(-1400 3025);
PAINT ORANGE (-1400 3025);
DISPLAY INVISIBLE (-1400 3025);
FORCEPROP 2 LAST SEC_TYPE 0402
J 0
(-1350 3250);
DISPLAY 1.021277 (-1350 3250);
PAINT ORANGE (-1350 3250);
DISPLAY INVISIBLE (-1350 3250);
FORCEPROP 2 LAST SEC 1
J 0
(-1350 3250);
DISPLAY 0.680851 (-1350 3250);
PAINT MONO (-1350 3250);
DISPLAY INVISIBLE (-1350 3250);
FORCEPROP 1 LAST PATH I164
J 0
(-1350 3200);
DISPLAY 0.978723 (-1350 3200);
PAINT WHITE (-1350 3200);
DISPLAY INVISIBLE (-1350 3200);
FORCEADD P3V3_STBY..1
(-1400 3325);
FORCEPROP 3 LASTPIN (-1400 3275) SIG_NAME P3V3_STBY\g
J 0
(-1390 3285);
DISPLAY 0.659574 (-1390 3285);
PAINT MONO (-1390 3285);
DISPLAY INVISIBLE (-1390 3285);
FORCEPROP 1 LAST HDL_POWER P3V3_STBY
J 0
(-1700 3200);
DISPLAY 0.872340 (-1700 3200);
PAINT ORANGE (-1700 3200);
DISPLAY INVISIBLE (-1700 3200);
FORCEPROP 1 LAST BODY_TYPE PLUMBING
J 0
(-1445 3282);
DISPLAY 0.340426 (-1445 3282);
PAINT GREEN (-1445 3282);
DISPLAY INVISIBLE (-1445 3282);
FORCEPROP 1 LAST PATH I165
J 0
(-1355 3327);
DISPLAY 0.340426 (-1355 3327);
PAINT GREEN (-1355 3327);
DISPLAY INVISIBLE (-1355 3327);
FORCEPROP 2 LAST CDS_LIB mstr_symbols
J 0
(-1400 3325);
PAINT ORANGE (-1400 3325);
DISPLAY INVISIBLE (-1400 3325);
FORCEPROP 1 LAST SIZE 1B
J 0
(-1355 3347);
DISPLAY 0.340426 (-1355 3347);
PAINT GREEN (-1355 3347);
DISPLAY INVISIBLE (-1355 3347);
FORCEPROP 1 LAST VOLTAGE 3.3V
J 0
(-1445 3282);
DISPLAY 0.340426 (-1445 3282);
PAINT SKYBLUE (-1445 3282);
DISPLAY INVISIBLE (-1445 3282);
FORCEADD P3V3_STBY..1
(-650 3600);
FORCEPROP 3 LASTPIN (-650 3550) SIG_NAME P3V3_STBY\g
J 0
(-640 3560);
DISPLAY 0.659574 (-640 3560);
PAINT MONO (-640 3560);
DISPLAY INVISIBLE (-640 3560);
FORCEPROP 1 LAST HDL_POWER P3V3_STBY
J 0
(-950 3475);
DISPLAY 0.872340 (-950 3475);
PAINT ORANGE (-950 3475);
DISPLAY INVISIBLE (-950 3475);
FORCEPROP 1 LAST BODY_TYPE PLUMBING
J 0
(-695 3557);
DISPLAY 0.340426 (-695 3557);
PAINT GREEN (-695 3557);
DISPLAY INVISIBLE (-695 3557);
FORCEPROP 1 LAST PATH I166
J 0
(-605 3602);
DISPLAY 0.340426 (-605 3602);
PAINT GREEN (-605 3602);
DISPLAY INVISIBLE (-605 3602);
FORCEPROP 2 LAST CDS_LIB mstr_symbols
J 0
(-650 3600);
PAINT ORANGE (-650 3600);
DISPLAY INVISIBLE (-650 3600);
FORCEPROP 1 LAST SIZE 1B
J 0
(-605 3622);
DISPLAY 0.340426 (-605 3622);
PAINT GREEN (-605 3622);
DISPLAY INVISIBLE (-605 3622);
FORCEPROP 1 LAST VOLTAGE 3.3V
J 0
(-695 3557);
DISPLAY 0.340426 (-695 3557);
PAINT SKYBLUE (-695 3557);
DISPLAY INVISIBLE (-695 3557);
FORCEADD 1K82R2F-1-GP..1
(-4700 4575);
FORCEPROP 2 LAST ATTRIBUTE 1.82KOHM
J 0
(-4675 4550);
DISPLAY 0.638298 (-4675 4550);
PAINT GREEN (-4675 4550);
FORCEPROP 2 LAST TOLERANCE 1%
J 0
(-4675 4500);
DISPLAY 0.638298 (-4675 4500);
PAINT GREEN (-4675 4500);
FORCEPROP 2 LAST RATED 1/16W
J 0
(-4675 4450);
DISPLAY 0.638298 (-4675 4450);
PAINT GREEN (-4675 4450);
FORCEPROP 1 LAST VALUE 1K82R2F-1-GP
J 0
(-4675 4600);
DISPLAY 0.617021 (-4675 4600);
PAINT GREEN (-4675 4600);
FORCEPROP 1 LAST LOCATION R1U28
J 0
(-4675 4655);
DISPLAY 0.617021 (-4675 4655);
PAINT GREEN (-4675 4655);
FORCEPROP 2 LASTPIN (-4700 4700) $PN 1
R 1
J 0
(-4710 4710);
DISPLAY 0.808511 (-4710 4710);
PAINT ORANGE (-4710 4710);
FORCEPROP 2 LAST PACK_SIZE 0402
J 0
(-4675 4400);
DISPLAY 0.638298 (-4675 4400);
PAINT GREEN (-4675 4400);
FORCEPROP 2 LASTPIN (-4700 4450) $PN 2
R 1
J 2
(-4710 4440);
DISPLAY 0.808511 (-4710 4440);
PAINT ORANGE (-4710 4440);
FORCEPROP 2 LAST SEC_TYPE SMD-RG
J 0
(-4675 4700);
DISPLAY 1.021277 (-4675 4700);
PAINT ORANGE (-4675 4700);
DISPLAY INVISIBLE (-4675 4700);
FORCEPROP 2 LAST SEC 1
J 0
(-4675 4700);
DISPLAY 0.680851 (-4675 4700);
PAINT MONO (-4675 4700);
DISPLAY INVISIBLE (-4675 4700);
FORCEPROP 1 LAST PACK_TYPE SMD-RG
J 0
(-4700 4575);
DISPLAY 0.617021 (-4700 4575);
PAINT GREEN (-4700 4575);
DISPLAY INVISIBLE (-4700 4575);
FORCEPROP 1 LAST CDS_LMAN_SYM_OUTLINE -50,75,50,-75
J 0
(-4700 4575);
DISPLAY 0.468085 (-4700 4575);
PAINT GREEN (-4700 4575);
DISPLAY INVISIBLE (-4700 4575);
FORCEPROP 2 LAST CDS_LIB w_hdl
J 0
(-4700 4575);
PAINT MONO (-4700 4575);
DISPLAY INVISIBLE (-4700 4575);
FORCEPROP 1 LAST PART_NUMBER 64.18215.6DL
J 0
(-4700 4575);
DISPLAY 0.617021 (-4700 4575);
PAINT GREEN (-4700 4575);
DISPLAY INVISIBLE (-4700 4575);
FORCEPROP 1 LAST PATH I169
J 0
(-4700 4575);
DISPLAY 0.617021 (-4700 4575);
PAINT GREEN (-4700 4575);
DISPLAY INVISIBLE (-4700 4575);
FORCEADD 1K82R2F-1-GP..1
(-2850 1375);
FORCEPROP 2 LAST ATTRIBUTE 1.82KOHM
J 0
(-2825 1350);
DISPLAY 0.638298 (-2825 1350);
PAINT GREEN (-2825 1350);
FORCEPROP 2 LAST RATED 1/16W
J 0
(-2825 1250);
DISPLAY 0.638298 (-2825 1250);
PAINT GREEN (-2825 1250);
FORCEPROP 2 LASTPIN (-2850 1500) $PN 1
R 1
J 0
(-2860 1510);
DISPLAY 0.808511 (-2860 1510);
PAINT ORANGE (-2860 1510);
FORCEPROP 2 LAST TOLERANCE 1%
J 0
(-2825 1300);
DISPLAY 0.638298 (-2825 1300);
PAINT GREEN (-2825 1300);
FORCEPROP 1 LAST VALUE 1K82R2F-1-GP
J 0
(-2825 1400);
DISPLAY 0.617021 (-2825 1400);
PAINT GREEN (-2825 1400);
FORCEPROP 1 LAST LOCATION R1U44
J 0
(-2825 1455);
DISPLAY 0.617021 (-2825 1455);
PAINT GREEN (-2825 1455);
FORCEPROP 2 LAST PACK_SIZE 0402
J 0
(-2825 1200);
DISPLAY 0.638298 (-2825 1200);
PAINT GREEN (-2825 1200);
FORCEPROP 2 LASTPIN (-2850 1250) $PN 2
R 1
J 2
(-2860 1240);
DISPLAY 0.808511 (-2860 1240);
PAINT ORANGE (-2860 1240);
FORCEPROP 2 LAST SEC_TYPE SMD-RG
J 0
(-2825 1500);
DISPLAY 1.021277 (-2825 1500);
PAINT ORANGE (-2825 1500);
DISPLAY INVISIBLE (-2825 1500);
FORCEPROP 2 LAST SEC 1
J 0
(-2825 1500);
DISPLAY 0.680851 (-2825 1500);
PAINT MONO (-2825 1500);
DISPLAY INVISIBLE (-2825 1500);
FORCEPROP 1 LAST PACK_TYPE SMD-RG
J 0
(-2850 1375);
DISPLAY 0.617021 (-2850 1375);
PAINT GREEN (-2850 1375);
DISPLAY INVISIBLE (-2850 1375);
FORCEPROP 1 LAST PATH I170
J 0
(-2850 1375);
DISPLAY 0.617021 (-2850 1375);
PAINT GREEN (-2850 1375);
DISPLAY INVISIBLE (-2850 1375);
FORCEPROP 1 LAST CDS_LMAN_SYM_OUTLINE -50,75,50,-75
J 0
(-2850 1375);
DISPLAY 0.468085 (-2850 1375);
PAINT GREEN (-2850 1375);
DISPLAY INVISIBLE (-2850 1375);
FORCEPROP 2 LAST CDS_LIB w_hdl
J 0
(-2850 1375);
PAINT MONO (-2850 1375);
DISPLAY INVISIBLE (-2850 1375);
FORCEPROP 1 LAST PART_NUMBER 64.18215.6DL
J 0
(-2850 1375);
DISPLAY 0.617021 (-2850 1375);
PAINT GREEN (-2850 1375);
DISPLAY INVISIBLE (-2850 1375);
FORCEADD 649R2F-GP..1
(-1125 1425);
FORCEPROP 2 LAST ATTRIBUTE 649OHM
J 0
(-1100 1450);
DISPLAY 0.638298 (-1100 1450);
PAINT GREEN (-1100 1450);
FORCEPROP 2 LAST TOLERANCE 1%
J 0
(-1100 1400);
DISPLAY 0.638298 (-1100 1400);
PAINT GREEN (-1100 1400);
FORCEPROP 2 LAST RATED 1/16W
J 0
(-1100 1350);
DISPLAY 0.638298 (-1100 1350);
PAINT GREEN (-1100 1350);
FORCEPROP 2 LASTPIN (-1125 1300) $PN 2
J 2
(-1135 1315);
DISPLAY 0.808511 (-1135 1315);
PAINT ORANGE (-1135 1315);
FORCEPROP 1 LAST VALUE 649R2F-GP
J 0
(-1100 1500);
DISPLAY 0.617021 (-1100 1500);
PAINT GREEN (-1100 1500);
FORCEPROP 2 LASTPIN (-1125 1550) $PN 1
J 0
(-1185 1510);
DISPLAY 0.808511 (-1185 1510);
PAINT ORANGE (-1185 1510);
FORCEPROP 1 LAST LOCATION R1U33
J 0
(-1100 1555);
DISPLAY 0.617021 (-1100 1555);
PAINT GREEN (-1100 1555);
FORCEPROP 2 LAST PACK_SIZE 0402
J 0
(-1100 1300);
DISPLAY 0.638298 (-1100 1300);
PAINT GREEN (-1100 1300);
FORCEPROP 1 LAST CDS_LMAN_SYM_OUTLINE -50,75,50,-75
J 0
(-1125 1425);
DISPLAY 0.468085 (-1125 1425);
PAINT GREEN (-1125 1425);
DISPLAY INVISIBLE (-1125 1425);
FORCEPROP 1 LAST PATH I171
J 0
(-1125 1425);
DISPLAY 0.617021 (-1125 1425);
PAINT GREEN (-1125 1425);
DISPLAY INVISIBLE (-1125 1425);
FORCEPROP 2 LAST CDS_LIB w_hdl
J 0
(-1125 1425);
PAINT MONO (-1125 1425);
DISPLAY INVISIBLE (-1125 1425);
FORCEPROP 1 LAST PART_NUMBER 64.64905.6DL
J 0
(-1125 1425);
DISPLAY 0.617021 (-1125 1425);
PAINT GREEN (-1125 1425);
DISPLAY INVISIBLE (-1125 1425);
FORCEPROP 2 LAST SEC_TYPE RCL_GP
J 0
(-1100 1550);
DISPLAY 1.021277 (-1100 1550);
PAINT ORANGE (-1100 1550);
DISPLAY INVISIBLE (-1100 1550);
FORCEPROP 2 LAST SEC 1
J 0
(-1100 1550);
DISPLAY 0.680851 (-1100 1550);
PAINT MONO (-1100 1550);
DISPLAY INVISIBLE (-1100 1550);
FORCEPROP 1 LAST PACK_TYPE RCL_GP
J 0
(-1125 1425);
DISPLAY 0.617021 (-1125 1425);
PAINT GREEN (-1125 1425);
DISPLAY INVISIBLE (-1125 1425);
FORCEADD RES..1
R 5
(-4825 1400);
FORCEPROP 1 LAST PACK_TYPE 0402
J 0
(-4775 1225);
DISPLAY 0.638298 (-4775 1225);
PAINT SKYBLUE (-4775 1225);
FORCEPROP 1 LAST TOLERANCE 1.0%
J 0
(-4775 1425);
DISPLAY 0.638298 (-4775 1425);
PAINT SKYBLUE (-4775 1425);
FORCEPROP 1 LASTPIN (-4825 1500) $PN 1
J 0
(-4813 1463);
DISPLAY 0.787234 (-4813 1463);
PAINT ORANGE (-4813 1463);
FORCEPROP 1 LASTPIN (-4825 1300) $PN 2
J 0
(-4813 1313);
DISPLAY 0.787234 (-4813 1313);
PAINT ORANGE (-4813 1313);
FORCEPROP 1 LAST LOCATION R1U38
J 0
(-4775 1525);
DISPLAY 0.638298 (-4775 1525);
PAINT SKYBLUE (-4775 1525);
FORCEPROP 1 LAST VALUE 3.48K
J 2
(-4675 1475);
DISPLAY 0.638298 (-4675 1475);
PAINT SKYBLUE (-4675 1475);
FORCEPROP 1 LAST WATTAGE 1/16W
J 2
(-4675 1375);
DISPLAY 0.638298 (-4675 1375);
PAINT SKYBLUE (-4675 1375);
FORCEPROP 1 LAST MATERIAL CHIP
J 0
(-4775 1325);
DISPLAY 0.638298 (-4775 1325);
PAINT SKYBLUE (-4775 1325);
FORCEPROP 1 LAST PART_NUMBER G21796-279
J 0
(-4775 1275);
DISPLAY 0.638298 (-4775 1275);
PAINT BLUE (-4775 1275);
FORCEPROP 2 LAST SEC 1
R 2
J 0
(-4875 1225);
DISPLAY 0.680851 (-4875 1225);
PAINT MONO (-4875 1225);
DISPLAY INVISIBLE (-4875 1225);
FORCEPROP 2 LAST SEC_TYPE 0402
R 2
J 0
(-4875 1225);
DISPLAY 1.021277 (-4875 1225);
PAINT ORANGE (-4875 1225);
DISPLAY INVISIBLE (-4875 1225);
FORCEPROP 2 LAST CDS_LIB mstr_discrete
R 3
J 0
(-4825 1400);
PAINT MONO (-4825 1400);
DISPLAY INVISIBLE (-4825 1400);
FORCEPROP 1 LAST PATH I172
R 3
J 0
(-4675 1450);
DISPLAY 0.978723 (-4675 1450);
PAINT WHITE (-4675 1450);
DISPLAY INVISIBLE (-4675 1450);
FORCEADD RES..1
R 5
(-2900 4625);
FORCEPROP 1 LAST TOLERANCE 1.0%
J 0
(-2850 4650);
DISPLAY 0.638298 (-2850 4650);
PAINT SKYBLUE (-2850 4650);
FORCEPROP 1 LAST VALUE 3.48K
J 2
(-2750 4700);
DISPLAY 0.638298 (-2750 4700);
PAINT SKYBLUE (-2750 4700);
FORCEPROP 1 LAST PART_NUMBER G21796-279
J 0
(-2850 4500);
DISPLAY 0.638298 (-2850 4500);
PAINT BLUE (-2850 4500);
FORCEPROP 1 LAST LOCATION R1U27
J 0
(-2850 4750);
DISPLAY 0.638298 (-2850 4750);
PAINT SKYBLUE (-2850 4750);
FORCEPROP 1 LAST PACK_TYPE 0402
J 0
(-2850 4450);
DISPLAY 0.638298 (-2850 4450);
PAINT SKYBLUE (-2850 4450);
FORCEPROP 1 LAST MATERIAL CHIP
J 0
(-2850 4550);
DISPLAY 0.638298 (-2850 4550);
PAINT SKYBLUE (-2850 4550);
FORCEPROP 1 LAST WATTAGE 1/16W
J 2
(-2750 4600);
DISPLAY 0.638298 (-2750 4600);
PAINT SKYBLUE (-2750 4600);
FORCEPROP 1 LASTPIN (-2900 4725) $PN 1
J 0
(-2888 4688);
DISPLAY 0.787234 (-2888 4688);
PAINT ORANGE (-2888 4688);
FORCEPROP 1 LASTPIN (-2900 4525) $PN 2
J 0
(-2888 4538);
DISPLAY 0.787234 (-2888 4538);
PAINT ORANGE (-2888 4538);
FORCEPROP 1 LAST PATH I173
R 3
J 0
(-2750 4675);
DISPLAY 0.978723 (-2750 4675);
PAINT WHITE (-2750 4675);
DISPLAY INVISIBLE (-2750 4675);
FORCEPROP 2 LAST SEC 1
R 2
J 0
(-2950 4450);
DISPLAY 0.680851 (-2950 4450);
PAINT MONO (-2950 4450);
DISPLAY INVISIBLE (-2950 4450);
FORCEPROP 2 LAST SEC_TYPE 0402
R 2
J 0
(-2950 4450);
DISPLAY 1.021277 (-2950 4450);
PAINT ORANGE (-2950 4450);
DISPLAY INVISIBLE (-2950 4450);
FORCEPROP 2 LAST CDS_LIB mstr_discrete
R 3
J 0
(-2900 4625);
PAINT MONO (-2900 4625);
DISPLAY INVISIBLE (-2900 4625);
FORCEADD OFFPAGE..2
(-4075 3400);
FORCEPROP 2 LAST $XR0 147 
J 0
(-3886 3400);
DISPLAY 0.638298 (-3886 3400);
PAINT MONO (-3886 3400);
FORCEPROP 1 LAST COMMENT_BODY TRUE
J 0
(-4120 3305);
DISPLAY 1.170213 (-4120 3305);
PAINT GREEN (-4120 3305);
DISPLAY INVISIBLE (-4120 3305);
FORCEPROP 1 LAST OFFPAGE TRUE
J 0
(-3750 3275);
PAINT GREEN (-3750 3275);
DISPLAY INVISIBLE (-3750 3275);
FORCEPROP 2 LAST PATH I55
J 0
(-3875 3450);
PAINT MONO (-3875 3450);
DISPLAY INVISIBLE (-3875 3450);
FORCEPROP 2 LAST CDS_LIB mstr_standard
J 0
(-4075 3400);
DISPLAY 1.361702 (-4075 3400);
PAINT ORANGE (-4075 3400);
DISPLAY INVISIBLE (-4075 3400);
FORCEADD CAP..1
(-4825 3250);
FORCEPROP 1 LAST PACK_TYPE 0402LF
J 0
(-4775 3050);
DISPLAY 0.617021 (-4775 3050);
PAINT SKYBLUE (-4775 3050);
FORCEPROP 1 LAST PART_NUMBER A36095-025
J 0
(-4775 3100);
DISPLAY 0.617021 (-4775 3100);
PAINT BLUE (-4775 3100);
FORCEPROP 1 LAST VALUE 47.0PF
J 0
(-4775 3300);
DISPLAY 0.617021 (-4775 3300);
PAINT SKYBLUE (-4775 3300);
FORCEPROP 1 LAST LOCATION C1U21
J 0
(-4775 3350);
DISPLAY 0.617021 (-4775 3350);
PAINT AQUA (-4775 3350);
FORCEPROP 1 LASTPIN (-4825 3350) $PN 1
J 0
(-4815 3330);
DISPLAY 0.617021 (-4815 3330);
PAINT MONO (-4815 3330);
FORCEPROP 1 LASTPIN (-4825 3150) $PN 2
J 0
(-4815 3130);
DISPLAY 0.617021 (-4815 3130);
PAINT MONO (-4815 3130);
FORCEPROP 1 LAST MATERIAL COG
J 0
(-4775 3150);
DISPLAY 0.617021 (-4775 3150);
PAINT SKYBLUE (-4775 3150);
FORCEPROP 1 LAST VOLTAGE 50V
J 0
(-4775 3250);
DISPLAY 0.617021 (-4775 3250);
PAINT SKYBLUE (-4775 3250);
FORCEPROP 1 LAST TOLERANCE 5%
J 0
(-4775 3200);
DISPLAY 0.617021 (-4775 3200);
PAINT SKYBLUE (-4775 3200);
FORCEPROP 2 LAST ROOM BMC_VOLT_MONITOR
J 0
(-4775 3400);
DISPLAY 1.021277 (-4775 3400);
PAINT ORANGE (-4775 3400);
DISPLAY INVISIBLE (-4775 3400);
FORCEPROP 1 LAST PATH I56
J 0
(-4775 3400);
DISPLAY 1.319149 (-4775 3400);
PAINT GREEN (-4775 3400);
DISPLAY INVISIBLE (-4775 3400);
FORCEPROP 2 LAST CDS_LOCATION C1U21
J 0
(-4775 3350);
DISPLAY 0.617021 (-4775 3350);
PAINT AQUA (-4775 3350);
DISPLAY INVISIBLE (-4775 3350);
FORCEPROP 2 LAST SEC 1
J 0
(-4775 3450);
DISPLAY 0.936170 (-4775 3450);
PAINT MONO (-4775 3450);
DISPLAY INVISIBLE (-4775 3450);
FORCEPROP 2 LAST BOM_COST SM_HM
J 0
(-4775 3450);
DISPLAY 1.021277 (-4775 3450);
PAINT ORANGE (-4775 3450);
DISPLAY INVISIBLE (-4775 3450);
FORCEPROP 2 LAST CDS_LIB mstr_discrete
J 0
(-4825 3250);
DISPLAY 1.361702 (-4825 3250);
PAINT ORANGE (-4825 3250);
DISPLAY INVISIBLE (-4825 3250);
FORCEPROP 2 LAST SEC_TYPE 0402LF
J 0
(-4775 3450);
PAINT MONO (-4775 3450);
DISPLAY INVISIBLE (-4775 3450);
FORCEADD FERRITE..4
(-4825 3600);
FORCEPROP 1 LAST MATERIAL FB
J 0
(-4764 3445);
DISPLAY 0.617021 (-4764 3445);
PAINT SKYBLUE (-4764 3445);
FORCEPROP 1 LAST LOCATION FB1U3
J 0
(-4765 3645);
DISPLAY 0.617021 (-4765 3645);
PAINT AQUA (-4765 3645);
FORCEPROP 1 LAST VALUE 30
J 0
(-4765 3595);
DISPLAY 0.617021 (-4765 3595);
PAINT SKYBLUE (-4765 3595);
FORCEPROP 1 LAST PACK_TYPE SMLF
J 0
(-4765 3495);
DISPLAY 0.617021 (-4765 3495);
PAINT SKYBLUE (-4765 3495);
FORCEPROP 1 LASTPIN (-4825 3500) $PN 1
J 0
(-4805 3500);
DISPLAY 0.617021 (-4805 3500);
PAINT MONO (-4805 3500);
FORCEPROP 1 LASTPIN (-4825 3700) $PN 2
J 0
(-4805 3670);
DISPLAY 0.617021 (-4805 3670);
PAINT MONO (-4805 3670);
FORCEPROP 1 LAST PART_NUMBER 693286-021
J 0
(-4765 3545);
DISPLAY 0.617021 (-4765 3545);
PAINT BLUE (-4765 3545);
FORCEPROP 2 LAST ROOM BMC_VOLT_MONITOR
J 0
(-4750 3675);
DISPLAY 1.021277 (-4750 3675);
PAINT ORANGE (-4750 3675);
DISPLAY INVISIBLE (-4750 3675);
FORCEPROP 1 LAST PATH I57
J 0
(-4760 3695);
DISPLAY 1.319149 (-4760 3695);
PAINT GREEN (-4760 3695);
DISPLAY INVISIBLE (-4760 3695);
FORCEPROP 2 LAST CDS_LOCATION FB1U3
J 0
(-4765 3645);
DISPLAY 0.617021 (-4765 3645);
PAINT AQUA (-4765 3645);
DISPLAY INVISIBLE (-4765 3645);
FORCEPROP 2 LAST SEC 1
J 0
(-4750 3750);
DISPLAY 0.936170 (-4750 3750);
PAINT MONO (-4750 3750);
DISPLAY INVISIBLE (-4750 3750);
FORCEPROP 2 LAST CDS_LIB mstr_discrete
J 0
(-4825 3600);
DISPLAY 1.361702 (-4825 3600);
PAINT ORANGE (-4825 3600);
DISPLAY INVISIBLE (-4825 3600);
FORCEPROP 2 LAST SEC_TYPE SMLF
J 0
(-4750 3750);
PAINT MONO (-4750 3750);
DISPLAY INVISIBLE (-4750 3750);
FORCEPROP 2 LAST BOM_COST SM_HM
J 0
(-4750 3725);
DISPLAY 1.021277 (-4750 3725);
PAINT ORANGE (-4750 3725);
DISPLAY INVISIBLE (-4750 3725);
FORCEADD GND..1
(-4825 3000);
FORCEPROP 3 LASTPIN (-4825 3050) SIG_NAME GND\g
J 0
(-4815 3060);
DISPLAY 0.659574 (-4815 3060);
PAINT MONO (-4815 3060);
DISPLAY INVISIBLE (-4815 3060);
FORCEPROP 1 LAST HDL_POWER GND
J 0
(-4825 3150);
DISPLAY 1.148936 (-4825 3150);
PAINT GREEN (-4825 3150);
DISPLAY INVISIBLE (-4825 3150);
FORCEPROP 1 LAST BODY_TYPE PLUMBING
J 0
(-4870 2957);
DISPLAY 0.340426 (-4870 2957);
PAINT GREEN (-4870 2957);
DISPLAY INVISIBLE (-4870 2957);
FORCEPROP 1 LAST PATH I58
J 0
(-4750 3000);
DISPLAY 1.170213 (-4750 3000);
PAINT GREEN (-4750 3000);
DISPLAY INVISIBLE (-4750 3000);
FORCEPROP 2 LAST CDS_LIB mstr_symbols
J 0
(-4825 3000);
DISPLAY 1.361702 (-4825 3000);
PAINT ORANGE (-4825 3000);
DISPLAY INVISIBLE (-4825 3000);
FORCEPROP 1 LAST SIZE 1B
J 0
(-4750 2950);
DISPLAY 1.148936 (-4750 2950);
PAINT GREEN (-4750 2950);
DISPLAY INVISIBLE (-4750 2950);
FORCEPROP 1 LAST VOLTAGE 0
J 0
(-4825 3000);
PAINT SKYBLUE (-4825 3000);
DISPLAY INVISIBLE (-4825 3000);
FORCEADD OFFPAGE..2
(-1900 1550);
FORCEPROP 2 LAST $XR0 147 
J 0
(-1711 1550);
DISPLAY 0.638298 (-1711 1550);
PAINT MONO (-1711 1550);
FORCEPROP 1 LAST COMMENT_BODY TRUE
J 0
(-1945 1455);
DISPLAY 1.170213 (-1945 1455);
PAINT GREEN (-1945 1455);
DISPLAY INVISIBLE (-1945 1455);
FORCEPROP 1 LAST OFFPAGE TRUE
J 0
(-1575 1425);
PAINT GREEN (-1575 1425);
DISPLAY INVISIBLE (-1575 1425);
FORCEPROP 2 LAST PATH I67
J 0
(-1700 1600);
PAINT MONO (-1700 1600);
DISPLAY INVISIBLE (-1700 1600);
FORCEPROP 2 LAST CDS_LIB mstr_standard
J 0
(-1900 1550);
DISPLAY 1.361702 (-1900 1550);
PAINT ORANGE (-1900 1550);
DISPLAY INVISIBLE (-1900 1550);
FORCEADD CAP..1
(-2500 1350);
FORCEPROP 1 LAST MATERIAL COG
J 0
(-2450 1250);
DISPLAY 0.617021 (-2450 1250);
PAINT SKYBLUE (-2450 1250);
FORCEPROP 1 LAST PART_NUMBER A36095-025
J 0
(-2450 1200);
DISPLAY 0.617021 (-2450 1200);
PAINT BLUE (-2450 1200);
FORCEPROP 1 LAST PACK_TYPE 0402LF
J 0
(-2450 1150);
DISPLAY 0.617021 (-2450 1150);
PAINT SKYBLUE (-2450 1150);
FORCEPROP 1 LAST LOCATION C9G21
J 0
(-2450 1450);
DISPLAY 0.617021 (-2450 1450);
PAINT AQUA (-2450 1450);
FORCEPROP 1 LAST VOLTAGE 50V
J 0
(-2450 1350);
DISPLAY 0.617021 (-2450 1350);
PAINT SKYBLUE (-2450 1350);
FORCEPROP 1 LASTPIN (-2500 1250) $PN 2
J 0
(-2490 1230);
DISPLAY 0.617021 (-2490 1230);
PAINT MONO (-2490 1230);
FORCEPROP 1 LASTPIN (-2500 1450) $PN 1
J 0
(-2490 1430);
DISPLAY 0.617021 (-2490 1430);
PAINT MONO (-2490 1430);
FORCEPROP 1 LAST TOLERANCE 5%
J 0
(-2450 1300);
DISPLAY 0.617021 (-2450 1300);
PAINT SKYBLUE (-2450 1300);
FORCEPROP 1 LAST VALUE 47.0PF
J 0
(-2450 1400);
DISPLAY 0.617021 (-2450 1400);
PAINT SKYBLUE (-2450 1400);
FORCEPROP 2 LAST ROOM BMC_VOLT_MONITOR
J 0
(-2450 1500);
DISPLAY 1.021277 (-2450 1500);
PAINT ORANGE (-2450 1500);
DISPLAY INVISIBLE (-2450 1500);
FORCEPROP 1 LAST PATH I68
J 0
(-2450 1500);
DISPLAY 1.319149 (-2450 1500);
PAINT GREEN (-2450 1500);
DISPLAY INVISIBLE (-2450 1500);
FORCEPROP 2 LAST CDS_LOCATION C9G21
J 0
(-2450 1450);
DISPLAY 0.617021 (-2450 1450);
PAINT AQUA (-2450 1450);
DISPLAY INVISIBLE (-2450 1450);
FORCEPROP 2 LAST SEC 1
J 0
(-2450 1550);
DISPLAY 0.936170 (-2450 1550);
PAINT MONO (-2450 1550);
DISPLAY INVISIBLE (-2450 1550);
FORCEPROP 2 LAST SEC_TYPE 0402LF
J 0
(-2450 1550);
PAINT MONO (-2450 1550);
DISPLAY INVISIBLE (-2450 1550);
FORCEPROP 2 LAST CDS_LIB mstr_discrete
J 0
(-2500 1350);
DISPLAY 1.361702 (-2500 1350);
PAINT ORANGE (-2500 1350);
DISPLAY INVISIBLE (-2500 1350);
FORCEPROP 2 LAST BOM_COST SM_HM
J 0
(-2450 1550);
DISPLAY 1.021277 (-2450 1550);
PAINT ORANGE (-2450 1550);
DISPLAY INVISIBLE (-2450 1550);
FORCEADD GND..1
(-2850 1100);
FORCEPROP 3 LASTPIN (-2850 1150) SIG_NAME GND\g
J 0
(-2840 1160);
DISPLAY 0.659574 (-2840 1160);
PAINT MONO (-2840 1160);
DISPLAY INVISIBLE (-2840 1160);
FORCEPROP 1 LAST HDL_POWER GND
J 0
(-2850 1250);
DISPLAY 1.148936 (-2850 1250);
PAINT GREEN (-2850 1250);
DISPLAY INVISIBLE (-2850 1250);
FORCEPROP 1 LAST BODY_TYPE PLUMBING
J 0
(-2895 1057);
DISPLAY 0.340426 (-2895 1057);
PAINT GREEN (-2895 1057);
DISPLAY INVISIBLE (-2895 1057);
FORCEPROP 1 LAST PATH I71
J 0
(-2775 1100);
DISPLAY 1.170213 (-2775 1100);
PAINT GREEN (-2775 1100);
DISPLAY INVISIBLE (-2775 1100);
FORCEPROP 2 LAST CDS_LIB mstr_symbols
J 0
(-2850 1100);
DISPLAY 1.361702 (-2850 1100);
PAINT ORANGE (-2850 1100);
DISPLAY INVISIBLE (-2850 1100);
FORCEPROP 1 LAST SIZE 1B
J 0
(-2775 1050);
DISPLAY 1.148936 (-2775 1050);
PAINT GREEN (-2775 1050);
DISPLAY INVISIBLE (-2775 1050);
FORCEPROP 1 LAST VOLTAGE 0
J 0
(-2850 1100);
PAINT SKYBLUE (-2850 1100);
DISPLAY INVISIBLE (-2850 1100);
FORCEADD OFFPAGE..2
(-200 1625);
FORCEPROP 2 LAST $XR0 147 
J 0
(-11 1625);
DISPLAY 0.638298 (-11 1625);
PAINT MONO (-11 1625);
FORCEPROP 1 LAST COMMENT_BODY TRUE
J 0
(-245 1530);
DISPLAY 1.170213 (-245 1530);
PAINT GREEN (-245 1530);
DISPLAY INVISIBLE (-245 1530);
FORCEPROP 1 LAST OFFPAGE TRUE
J 0
(125 1500);
PAINT GREEN (125 1500);
DISPLAY INVISIBLE (125 1500);
FORCEPROP 2 LAST PATH I79
J 0
(0 1675);
PAINT MONO (0 1675);
DISPLAY INVISIBLE (0 1675);
FORCEPROP 2 LAST CDS_LIB mstr_standard
J 0
(-200 1625);
DISPLAY 1.361702 (-200 1625);
PAINT ORANGE (-200 1625);
DISPLAY INVISIBLE (-200 1625);
FORCEADD CAP..1
(-775 1450);
FORCEPROP 1 LAST PACK_TYPE 0402LF
J 0
(-725 1250);
DISPLAY 0.617021 (-725 1250);
PAINT SKYBLUE (-725 1250);
FORCEPROP 1 LAST MATERIAL COG
J 0
(-725 1350);
DISPLAY 0.617021 (-725 1350);
PAINT SKYBLUE (-725 1350);
FORCEPROP 1 LAST PART_NUMBER A36095-025
J 0
(-725 1300);
DISPLAY 0.617021 (-725 1300);
PAINT BLUE (-725 1300);
FORCEPROP 1 LASTPIN (-775 1350) $PN 2
J 0
(-765 1330);
DISPLAY 0.617021 (-765 1330);
PAINT MONO (-765 1330);
FORCEPROP 1 LAST VALUE 47.0PF
J 0
(-725 1500);
DISPLAY 0.617021 (-725 1500);
PAINT SKYBLUE (-725 1500);
FORCEPROP 1 LAST LOCATION C9G17
J 0
(-725 1550);
DISPLAY 0.617021 (-725 1550);
PAINT AQUA (-725 1550);
FORCEPROP 1 LASTPIN (-775 1550) $PN 1
J 0
(-765 1530);
DISPLAY 0.617021 (-765 1530);
PAINT MONO (-765 1530);
FORCEPROP 1 LAST VOLTAGE 50V
J 0
(-725 1450);
DISPLAY 0.617021 (-725 1450);
PAINT SKYBLUE (-725 1450);
FORCEPROP 1 LAST TOLERANCE 5%
J 0
(-725 1400);
DISPLAY 0.617021 (-725 1400);
PAINT SKYBLUE (-725 1400);
FORCEPROP 2 LAST ROOM BMC_VOLT_MONITOR
J 0
(-725 1600);
DISPLAY 1.021277 (-725 1600);
PAINT ORANGE (-725 1600);
DISPLAY INVISIBLE (-725 1600);
FORCEPROP 1 LAST PATH I80
J 0
(-725 1600);
DISPLAY 1.319149 (-725 1600);
PAINT GREEN (-725 1600);
DISPLAY INVISIBLE (-725 1600);
FORCEPROP 2 LAST CDS_LOCATION C9G17
J 0
(-725 1550);
DISPLAY 0.617021 (-725 1550);
PAINT AQUA (-725 1550);
DISPLAY INVISIBLE (-725 1550);
FORCEPROP 2 LAST SEC 1
J 0
(-725 1650);
DISPLAY 0.936170 (-725 1650);
PAINT MONO (-725 1650);
DISPLAY INVISIBLE (-725 1650);
FORCEPROP 2 LAST SEC_TYPE 0402LF
J 0
(-725 1650);
PAINT MONO (-725 1650);
DISPLAY INVISIBLE (-725 1650);
FORCEPROP 2 LAST CDS_LIB mstr_discrete
J 0
(-775 1450);
DISPLAY 1.361702 (-775 1450);
PAINT ORANGE (-775 1450);
DISPLAY INVISIBLE (-775 1450);
FORCEPROP 2 LAST BOM_COST SM_HM
J 0
(-725 1650);
DISPLAY 1.021277 (-725 1650);
PAINT ORANGE (-725 1650);
DISPLAY INVISIBLE (-725 1650);
FORCEADD RES..2
(-1125 1825);
FORCEPROP 1 LAST WATTAGE 1/16W
J 0
(-1085 1800);
DISPLAY 0.617021 (-1085 1800);
PAINT SKYBLUE (-1085 1800);
FORCEPROP 1 LAST TOLERANCE 1%
J 0
(-1080 1850);
DISPLAY 0.617021 (-1080 1850);
PAINT SKYBLUE (-1080 1850);
FORCEPROP 1 LASTPIN (-1125 1925) $PN 1
J 0
(-1120 1887);
DISPLAY 0.617021 (-1120 1887);
PAINT MONO (-1120 1887);
FORCEPROP 1 LAST PACK_TYPE 0402
J 0
(-1085 1650);
DISPLAY 0.617021 (-1085 1650);
PAINT SKYBLUE (-1085 1650);
FORCEPROP 1 LASTPIN (-1125 1725) $PN 2
J 0
(-1120 1735);
DISPLAY 0.617021 (-1120 1735);
PAINT MONO (-1120 1735);
FORCEPROP 1 LAST LOCATION R1U32
J 0
(-1080 1950);
DISPLAY 0.617021 (-1080 1950);
PAINT AQUA (-1080 1950);
FORCEPROP 1 LAST VALUE 5.11K
J 0
(-1080 1900);
DISPLAY 0.617021 (-1080 1900);
PAINT SKYBLUE (-1080 1900);
FORCEPROP 1 LAST MATERIAL CHIP
J 0
(-1085 1750);
DISPLAY 0.617021 (-1085 1750);
PAINT SKYBLUE (-1085 1750);
FORCEPROP 1 LAST PART_NUMBER G21796-140
J 0
(-1085 1700);
DISPLAY 0.617021 (-1085 1700);
PAINT BLUE (-1085 1700);
FORCEPROP 2 LAST ROOM BMC_VOLT_MONITOR
J 0
(-1075 2000);
DISPLAY 1.021277 (-1075 2000);
PAINT ORANGE (-1075 2000);
DISPLAY INVISIBLE (-1075 2000);
FORCEPROP 1 LAST PATH I82
J 0
(-1075 2000);
DISPLAY 1.319149 (-1075 2000);
PAINT GREEN (-1075 2000);
DISPLAY INVISIBLE (-1075 2000);
FORCEPROP 2 LAST CDS_LOCATION R1U32
J 0
(-1080 1950);
DISPLAY 0.617021 (-1080 1950);
PAINT AQUA (-1080 1950);
DISPLAY INVISIBLE (-1080 1950);
FORCEPROP 2 LAST SEC 1
J 0
(-1075 2050);
DISPLAY 0.936170 (-1075 2050);
PAINT MONO (-1075 2050);
DISPLAY INVISIBLE (-1075 2050);
FORCEPROP 2 LAST BOM_COST SM_HM
J 0
(-1075 2050);
DISPLAY 1.021277 (-1075 2050);
PAINT ORANGE (-1075 2050);
DISPLAY INVISIBLE (-1075 2050);
FORCEPROP 2 LAST CDS_LIB mstr_discrete
J 0
(-1125 1825);
DISPLAY 1.361702 (-1125 1825);
PAINT ORANGE (-1125 1825);
DISPLAY INVISIBLE (-1125 1825);
FORCEPROP 2 LAST SEC_TYPE 0402
J 0
(-1075 2050);
PAINT MONO (-1075 2050);
DISPLAY INVISIBLE (-1075 2050);
FORCEADD GND..1
(-1125 1175);
FORCEPROP 3 LASTPIN (-1125 1225) SIG_NAME GND\g
J 0
(-1115 1235);
DISPLAY 0.659574 (-1115 1235);
PAINT MONO (-1115 1235);
DISPLAY INVISIBLE (-1115 1235);
FORCEPROP 1 LAST HDL_POWER GND
J 0
(-1125 1325);
DISPLAY 1.148936 (-1125 1325);
PAINT GREEN (-1125 1325);
DISPLAY INVISIBLE (-1125 1325);
FORCEPROP 1 LAST BODY_TYPE PLUMBING
J 0
(-1170 1132);
DISPLAY 0.340426 (-1170 1132);
PAINT GREEN (-1170 1132);
DISPLAY INVISIBLE (-1170 1132);
FORCEPROP 1 LAST PATH I84
J 0
(-1050 1175);
DISPLAY 1.170213 (-1050 1175);
PAINT GREEN (-1050 1175);
DISPLAY INVISIBLE (-1050 1175);
FORCEPROP 2 LAST CDS_LIB mstr_symbols
J 0
(-1125 1175);
DISPLAY 1.361702 (-1125 1175);
PAINT ORANGE (-1125 1175);
DISPLAY INVISIBLE (-1125 1175);
FORCEPROP 1 LAST SIZE 1B
J 0
(-1050 1125);
DISPLAY 1.148936 (-1050 1125);
PAINT GREEN (-1050 1125);
DISPLAY INVISIBLE (-1050 1125);
FORCEPROP 1 LAST VOLTAGE 0
J 0
(-1125 1175);
PAINT SKYBLUE (-1125 1175);
DISPLAY INVISIBLE (-1125 1175);
FORCEADD OFFPAGE..2
(-3925 1600);
FORCEPROP 2 LAST $XR0 147 
J 0
(-3736 1600);
DISPLAY 0.638298 (-3736 1600);
PAINT MONO (-3736 1600);
FORCEPROP 1 LAST COMMENT_BODY TRUE
J 0
(-3970 1505);
DISPLAY 1.170213 (-3970 1505);
PAINT GREEN (-3970 1505);
DISPLAY INVISIBLE (-3970 1505);
FORCEPROP 1 LAST OFFPAGE TRUE
J 0
(-3600 1475);
PAINT GREEN (-3600 1475);
DISPLAY INVISIBLE (-3600 1475);
FORCEPROP 2 LAST PATH I85
J 0
(-3725 1650);
PAINT MONO (-3725 1650);
DISPLAY INVISIBLE (-3725 1650);
FORCEPROP 2 LAST CDS_LIB mstr_standard
J 0
(-3925 1600);
DISPLAY 1.361702 (-3925 1600);
PAINT ORANGE (-3925 1600);
DISPLAY INVISIBLE (-3925 1600);
FORCEADD CAP..1
(-4475 1425);
FORCEPROP 1 LAST VALUE 47.0PF
J 0
(-4425 1475);
DISPLAY 0.617021 (-4425 1475);
PAINT SKYBLUE (-4425 1475);
FORCEPROP 1 LAST VOLTAGE 50V
J 0
(-4425 1425);
DISPLAY 0.617021 (-4425 1425);
PAINT SKYBLUE (-4425 1425);
FORCEPROP 1 LAST TOLERANCE 5%
J 0
(-4425 1375);
DISPLAY 0.617021 (-4425 1375);
PAINT SKYBLUE (-4425 1375);
FORCEPROP 1 LAST MATERIAL COG
J 0
(-4425 1325);
DISPLAY 0.617021 (-4425 1325);
PAINT SKYBLUE (-4425 1325);
FORCEPROP 1 LAST LOCATION C9G20
J 0
(-4425 1525);
DISPLAY 0.617021 (-4425 1525);
PAINT AQUA (-4425 1525);
FORCEPROP 1 LASTPIN (-4475 1325) $PN 2
J 0
(-4465 1305);
DISPLAY 0.617021 (-4465 1305);
PAINT MONO (-4465 1305);
FORCEPROP 1 LASTPIN (-4475 1525) $PN 1
J 0
(-4465 1505);
DISPLAY 0.617021 (-4465 1505);
PAINT MONO (-4465 1505);
FORCEPROP 1 LAST PART_NUMBER A36095-025
J 0
(-4425 1275);
DISPLAY 0.617021 (-4425 1275);
PAINT BLUE (-4425 1275);
FORCEPROP 1 LAST PACK_TYPE 0402LF
J 0
(-4425 1225);
DISPLAY 0.617021 (-4425 1225);
PAINT SKYBLUE (-4425 1225);
FORCEPROP 2 LAST BOM_COST SM_HM
J 0
(-4425 1625);
DISPLAY 1.021277 (-4425 1625);
PAINT ORANGE (-4425 1625);
DISPLAY INVISIBLE (-4425 1625);
FORCEPROP 2 LAST CDS_LIB mstr_discrete
J 0
(-4475 1425);
DISPLAY 1.361702 (-4475 1425);
PAINT ORANGE (-4475 1425);
DISPLAY INVISIBLE (-4475 1425);
FORCEPROP 2 LAST SEC_TYPE 0402LF
J 0
(-4425 1625);
PAINT MONO (-4425 1625);
DISPLAY INVISIBLE (-4425 1625);
FORCEPROP 2 LAST SEC 1
J 0
(-4425 1625);
DISPLAY 0.936170 (-4425 1625);
PAINT MONO (-4425 1625);
DISPLAY INVISIBLE (-4425 1625);
FORCEPROP 2 LAST CDS_LOCATION C9G20
J 0
(-4425 1525);
DISPLAY 0.617021 (-4425 1525);
PAINT AQUA (-4425 1525);
DISPLAY INVISIBLE (-4425 1525);
FORCEPROP 1 LAST PATH I86
J 0
(-4425 1575);
DISPLAY 1.319149 (-4425 1575);
PAINT GREEN (-4425 1575);
DISPLAY INVISIBLE (-4425 1575);
FORCEPROP 2 LAST ROOM BMC_VOLT_MONITOR
J 0
(-4425 1575);
DISPLAY 1.021277 (-4425 1575);
PAINT ORANGE (-4425 1575);
DISPLAY INVISIBLE (-4425 1575);
FORCEADD RES..2
(-4825 1800);
FORCEPROP 1 LAST PACK_TYPE 0402
J 0
(-4785 1625);
DISPLAY 0.617021 (-4785 1625);
PAINT SKYBLUE (-4785 1625);
FORCEPROP 1 LAST MATERIAL CHIP
J 0
(-4785 1725);
DISPLAY 0.617021 (-4785 1725);
PAINT SKYBLUE (-4785 1725);
FORCEPROP 1 LASTPIN (-4825 1900) $PN 1
J 0
(-4820 1862);
DISPLAY 0.617021 (-4820 1862);
PAINT MONO (-4820 1862);
FORCEPROP 1 LAST LOCATION R1U39
J 0
(-4780 1925);
DISPLAY 0.617021 (-4780 1925);
PAINT AQUA (-4780 1925);
FORCEPROP 1 LAST PART_NUMBER G21796-140
J 0
(-4785 1675);
DISPLAY 0.617021 (-4785 1675);
PAINT BLUE (-4785 1675);
FORCEPROP 1 LASTPIN (-4825 1700) $PN 2
J 0
(-4820 1710);
DISPLAY 0.617021 (-4820 1710);
PAINT MONO (-4820 1710);
FORCEPROP 1 LAST VALUE 5.11K
J 0
(-4780 1875);
DISPLAY 0.617021 (-4780 1875);
PAINT SKYBLUE (-4780 1875);
FORCEPROP 1 LAST TOLERANCE 1%
J 0
(-4780 1825);
DISPLAY 0.617021 (-4780 1825);
PAINT SKYBLUE (-4780 1825);
FORCEPROP 1 LAST WATTAGE 1/16W
J 0
(-4785 1775);
DISPLAY 0.617021 (-4785 1775);
PAINT SKYBLUE (-4785 1775);
FORCEPROP 2 LAST ROOM BMC_VOLT_MONITOR
J 0
(-4775 1975);
DISPLAY 1.021277 (-4775 1975);
PAINT ORANGE (-4775 1975);
DISPLAY INVISIBLE (-4775 1975);
FORCEPROP 1 LAST PATH I88
J 0
(-4775 1975);
DISPLAY 1.319149 (-4775 1975);
PAINT GREEN (-4775 1975);
DISPLAY INVISIBLE (-4775 1975);
FORCEPROP 2 LAST CDS_LOCATION R1U39
J 0
(-4780 1925);
DISPLAY 0.617021 (-4780 1925);
PAINT AQUA (-4780 1925);
DISPLAY INVISIBLE (-4780 1925);
FORCEPROP 2 LAST SEC 1
J 0
(-4775 2025);
DISPLAY 0.936170 (-4775 2025);
PAINT MONO (-4775 2025);
DISPLAY INVISIBLE (-4775 2025);
FORCEPROP 2 LAST BOM_COST SM_HM
J 0
(-4775 2025);
DISPLAY 1.021277 (-4775 2025);
PAINT ORANGE (-4775 2025);
DISPLAY INVISIBLE (-4775 2025);
FORCEPROP 2 LAST CDS_LIB mstr_discrete
J 0
(-4825 1800);
DISPLAY 1.361702 (-4825 1800);
PAINT ORANGE (-4825 1800);
DISPLAY INVISIBLE (-4825 1800);
FORCEPROP 2 LAST SEC_TYPE 0402
J 0
(-4775 2025);
PAINT MONO (-4775 2025);
DISPLAY INVISIBLE (-4775 2025);
FORCEADD GND..1
(-4825 1150);
FORCEPROP 3 LASTPIN (-4825 1200) SIG_NAME GND\g
J 0
(-4815 1210);
DISPLAY 0.659574 (-4815 1210);
PAINT MONO (-4815 1210);
DISPLAY INVISIBLE (-4815 1210);
FORCEPROP 1 LAST HDL_POWER GND
J 0
(-4825 1300);
DISPLAY 1.148936 (-4825 1300);
PAINT GREEN (-4825 1300);
DISPLAY INVISIBLE (-4825 1300);
FORCEPROP 1 LAST BODY_TYPE PLUMBING
J 0
(-4870 1107);
DISPLAY 0.340426 (-4870 1107);
PAINT GREEN (-4870 1107);
DISPLAY INVISIBLE (-4870 1107);
FORCEPROP 1 LAST PATH I90
J 0
(-4750 1150);
DISPLAY 1.170213 (-4750 1150);
PAINT GREEN (-4750 1150);
DISPLAY INVISIBLE (-4750 1150);
FORCEPROP 2 LAST CDS_LIB mstr_symbols
J 0
(-4825 1150);
DISPLAY 1.361702 (-4825 1150);
PAINT ORANGE (-4825 1150);
DISPLAY INVISIBLE (-4825 1150);
FORCEPROP 1 LAST SIZE 1B
J 0
(-4750 1100);
DISPLAY 1.148936 (-4750 1100);
PAINT GREEN (-4750 1100);
DISPLAY INVISIBLE (-4750 1100);
FORCEPROP 1 LAST VOLTAGE 0
J 0
(-4825 1150);
PAINT SKYBLUE (-4825 1150);
DISPLAY INVISIBLE (-4825 1150);
FORCEADD DESIGN_NOTE..1
(700 3775);
FORCEPROP 0 LAST L2 DUE TO ITS LOWER VGS(TH) THAN THE C79254-001
J 0
(500 3575);
DISPLAY 1.021277 (500 3575);
PAINT ORANGE (500 3575);
FORCEPROP 0 LAST L1 E40049-001 WAS USED INSTEAD OF A C79254-001
J 0
(500 3650);
DISPLAY 1.021277 (500 3650);
PAINT ORANGE (500 3650);
FORCEPROP 0 LAST L3 FETS.
J 0
(500 3500);
DISPLAY 1.021277 (500 3500);
PAINT ORANGE (500 3500);
FORCEPROP 1 LAST COMMENT_BODY TRUE
J 0
(725 3875);
DISPLAY 0.978723 (725 3875);
PAINT ORANGE (725 3875);
DISPLAY INVISIBLE (725 3875);
FORCEPROP 2 LAST CDS_LIB mstr_symbols
J 0
(700 3775);
PAINT ORANGE (700 3775);
DISPLAY INVISIBLE (700 3775);
FORCEADD INTEL_CORP_BPAGE..1
(2650 500);
FORCEPROP 1 LAST CDS_CON_LAST_MODIFIED Fri Jun 16 17:49:02 2017
J 0
(1225 825);
PAINT ORANGE (1225 825);
DISPLAY INVISIBLE (1225 825);
FORCEPROP 1 LAST CUSTOM_TXT_CDS <CURRENT_DESIGN_SHEET> OF <TOTAL_DESIGN_SHEETS>
J 0
(2150 525);
PAINT ORANGE (2150 525);
FORCEPROP 1 LAST CUSTOM_TXT_CDS <CON_LAST_MODIFIED>
J 0
(-1350 600);
PAINT ORANGE (-1350 600);
FORCEPROP 2 LAST CUSTOM_TXT_CDS <XR_PAGE_TITLE>
J 0
(-5240 5750);
DISPLAY 0.638298 (-5240 5750);
PAINT PINK (-5240 5750);
DISPLAY INVISIBLE (-5240 5750);
FORCEPROP 1 LAST SCH_TITLE VOLTAGE MONITORING
J 0
(-5300 550);
DISPLAY 1.212766 (-5300 550);
PAINT ORANGE (-5300 550);
FORCEPROP 1 LAST COMMENT_BODY TRUE
J 0
(2662 512);
DISPLAY 0.468085 (2662 512);
PAINT GREEN (2662 512);
DISPLAY INVISIBLE (2662 512);
FORCEPROP 2 LAST PAGE_BORDER TRUE
J 0
(-5240 5750);
DISPLAY 0.851064 (-5240 5750);
PAINT PINK (-5240 5750);
DISPLAY INVISIBLE (-5240 5750);
FORCEPROP 2 LAST CDS_LIB mstr_symbols
J 0
(2650 500);
PAINT MONO (2650 500);
DISPLAY INVISIBLE (2650 500);
FORCEPROP 2 LAST CDS_XR_PAGE_TITLE CR-169 : @BASEBOARD_FAB2_LIB.BASEBOARD_FAB2(SCH_1):PAGE169
J 0
(-5240 5750);
DISPLAY 0.638298 (-5240 5750);
PAINT PINK (-5240 5750);
DISPLAY INVISIBLE (-5240 5750);
FORCEADD CAD_NOTE..1
(-800 1150);
FORCEPROP 0 LAST L1 AVIN SCALING RESISTORS SHOULD BE PLACED AT THE VOLTAGE RAIL SOURCE
J 0
(-950 1025);
DISPLAY 0.617021 (-950 1025);
PAINT WHITE (-950 1025);
FORCEPROP 0 LAST L2 47PF BYPASS CAP SHOULD BE LOCATED NEAR THE BMC
J 0
(-950 974);
DISPLAY 0.617021 (-950 974);
PAINT WHITE (-950 974);
FORCEPROP 1 LAST COMMENT_BODY TRUE
J 0
(-775 1250);
DISPLAY 1.361702 (-775 1250);
PAINT WHITE (-775 1250);
DISPLAY INVISIBLE (-775 1250);
FORCEPROP 2 LAST CDS_LIB mstr_symbols
J 0
(-800 1150);
PAINT WHITE (-800 1150);
DISPLAY INVISIBLE (-800 1150);
WIRE 16 -1 (400 2550)(400 2625);
WIRE 16 -1 (800 2550)(800 2600);
WIRE 16 -1 (-2850 1850)(-2850 1925);
WIRE 16 -1 (-4825 3725)(-4825 3700);
FORCEPROP 0 LAST CDS_PHYS_NET_NAME <<OCC_ONLY>>
J 1
(-4825 3750);
PAINT ORANGE (-4825 3750);
DISPLAY INVISIBLE (-4825 3750);
WIRE 16 -1 (-4825 1950)(-4825 1900);
WIRE 16 -1 (-1125 1975)(-1125 1925);
WIRE 16 -1 (-4700 4350)(-4700 4375);
WIRE 16 -1 (-4350 4375)(-4700 4375);
WIRE 16 -1 (-4700 4450)(-4700 4375);
WIRE 16 -1 (-4350 4450)(-4350 4375);
WIRE 16 -1 (-4700 5050)(-4700 5125);
WIRE 16 -1 (-2900 4400)(-2900 4450);
WIRE 16 -1 (-2550 4450)(-2900 4450);
WIRE 16 -1 (-2900 4525)(-2900 4450);
WIRE 16 -1 (-2550 4500)(-2550 4450);
WIRE 16 -1 (-2900 5150)(-2900 5100);
WIRE 16 -1 (800 1975)(800 1950);
FORCEPROP 0 LAST CDS_PHYS_NET_NAME <<OCC_ONLY>>
J 1
(800 2000);
PAINT ORANGE (800 2000);
DISPLAY INVISIBLE (800 2000);
WIRE 16 -1 (800 1375)(800 1300);
WIRE 16 -1 (-875 2700)(-875 2575);
WIRE 16 -1 (-1400 3125)(-1400 3275);
WIRE 16 -1 (-650 3475)(-650 3550);
WIRE 16 -1 (-4825 3050)(-4825 3150);
WIRE 16 -1 (-2850 1150)(-2850 1175);
WIRE 16 -1 (-2500 1175)(-2850 1175);
WIRE 16 -1 (-2850 1250)(-2850 1175);
WIRE 16 -1 (-2500 1250)(-2500 1175);
WIRE 16 -1 (-1125 1225)(-1125 1250);
WIRE 16 -1 (-775 1250)(-1125 1250);
WIRE 16 -1 (-1125 1300)(-1125 1250);
WIRE 16 -1 (-775 1350)(-775 1250);
WIRE 16 -1 (-4825 1200)(-4825 1225);
WIRE 16 -1 (-4475 1225)(-4825 1225);
WIRE 16 -1 (-4825 1300)(-4825 1225);
WIRE 16 -1 (-4475 1325)(-4475 1225);
WIRE 16 -1 (800 2800)(800 2900);
WIRE 16 -1 (1175 2900)(800 2900);
FORCEPROP 0 LAST CDS_PHYS_NET_NAME <<OCC_ONLY>>
J 1
(975 2950);
PAINT ORANGE (975 2950);
DISPLAY INVISIBLE (975 2950);
FORCEPROP 0 LAST VOLTAGE +1V
J 0
(975 3000);
DISPLAY 1.021277 (975 3000);
PAINT SKYBLUE (975 3000);
DISPLAY INVISIBLE (975 3000);
WIRE 16 -1 (400 2825)(400 2900);
WIRE 16 -1 (800 2900)(400 2900);
FORCEPROP 2 LAST SIG_NAME A_P3V_BAT_SCALED
J 0
(665 2910);
DISPLAY 0.617021 (665 2910);
PAINT ORANGE (665 2910);
WIRE 16 -1 (200 2900)(200 3025);
WIRE 16 -1 (200 2900)(400 2900);
WIRE 16 -1 (-4350 4650)(-4350 4750);
WIRE 16 -1 (-4000 4750)(-4350 4750);
FORCEPROP 2 LAST SIG_NAME A_P5V_SCALED
J 0
(-4325 4760);
DISPLAY 0.617021 (-4325 4760);
PAINT ORANGE (-4325 4760);
WIRE 16 -1 (-4700 4850)(-4700 4750);
WIRE 16 -1 (-4700 4700)(-4700 4750);
WIRE 16 -1 (-4700 4750)(-4350 4750);
FORCEPROP 0 LAST VOLTAGE +2V
J 0
(-4450 4800);
DISPLAY 1.021277 (-4450 4800);
PAINT SKYBLUE (-4450 4800);
DISPLAY INVISIBLE (-4450 4800);
WIRE 3 2175 (-4825 5325)(-1475 5325);
WIRE 3 2175 (-1475 4225)(-1475 5325);
WIRE 3 2175 (-4825 4225)(-4825 5325);
WIRE 3 2175 (-4825 4225)(-1475 4225);
WIRE 16 -1 (-2500 1450)(-2500 1550);
WIRE 16 -1 (-1950 1550)(-2500 1550);
FORCEPROP 0 LAST CDS_PHYS_NET_NAME <<OCC_ONLY>>
J 1
(-2475 1600);
PAINT ORANGE (-2475 1600);
DISPLAY INVISIBLE (-2475 1600);
FORCEPROP 0 LAST VOLTAGE +2V
J 0
(-2475 1650);
DISPLAY 1.021277 (-2475 1650);
PAINT SKYBLUE (-2475 1650);
DISPLAY INVISIBLE (-2475 1650);
FORCEPROP 2 LAST SIG_NAME A_P5V_STBY_SCALED
J 0
(-2350 1560);
DISPLAY 0.617021 (-2350 1560);
PAINT ORANGE (-2350 1560);
WIRE 16 -1 (-2850 1500)(-2850 1550);
WIRE 16 -1 (-2850 1650)(-2850 1550);
WIRE 16 -1 (-2850 1550)(-2500 1550);
WIRE 3 2175 (-5150 2125)(500 2125);
WIRE 3 2175 (500 950)(500 2125);
WIRE 3 2175 (-5150 950)(-5150 2125);
WIRE 3 2175 (-5150 950)(500 950);
WIRE 16 -1 (-4825 1500)(-4825 1600);
WIRE 16 -1 (-4825 1600)(-4825 1700);
WIRE 16 -1 (-4825 1600)(-4475 1600);
WIRE 16 -1 (-3975 1600)(-4475 1600);
FORCEPROP 0 LAST CDS_PHYS_NET_NAME <<OCC_ONLY>>
J 1
(-4475 1650);
PAINT ORANGE (-4475 1650);
DISPLAY INVISIBLE (-4475 1650);
FORCEPROP 0 LAST VOLTAGE +1.8V
J 0
(-4450 1675);
DISPLAY 1.021277 (-4450 1675);
PAINT SKYBLUE (-4450 1675);
DISPLAY INVISIBLE (-4450 1675);
FORCEPROP 2 LAST SIG_NAME A_P3V3_STBY_SCALED
J 0
(-4450 1610);
DISPLAY 0.617021 (-4450 1610);
PAINT ORANGE (-4450 1610);
WIRE 16 -1 (-4475 1525)(-4475 1600);
WIRE 16 -1 (-4825 3350)(-4825 3400);
WIRE 16 -1 (-4825 3400)(-4825 3500);
WIRE 16 -1 (-4125 3400)(-4825 3400);
FORCEPROP 0 LAST CDS_PHYS_NET_NAME <<OCC_ONLY>>
J 1
(-4450 3450);
PAINT ORANGE (-4450 3450);
DISPLAY INVISIBLE (-4450 3450);
FORCEPROP 0 LAST VOLTAGE +1.2V
J 0
(-4200 3475);
DISPLAY 1.021277 (-4200 3475);
PAINT SKYBLUE (-4200 3475);
DISPLAY INVISIBLE (-4200 3475);
FORCEPROP 2 LAST SIG_NAME A_P1V05_STBY_PCH_SENSOR
J 0
(-4675 3410);
DISPLAY 0.617021 (-4675 3410);
PAINT ORANGE (-4675 3410);
WIRE 16 -1 (-1125 1625)(-1125 1725);
WIRE 16 -1 (-1125 1550)(-1125 1625);
WIRE 16 -1 (-1125 1625)(-775 1625);
WIRE 16 -1 (-775 1550)(-775 1625);
WIRE 16 -1 (-250 1625)(-775 1625);
FORCEPROP 0 LAST CDS_PHYS_NET_NAME <<OCC_ONLY>>
J 1
(-350 1675);
PAINT ORANGE (-350 1675);
DISPLAY INVISIBLE (-350 1675);
FORCEPROP 0 LAST VOLTAGE +2V
J 0
(-350 1725);
DISPLAY 1.021277 (-350 1725);
PAINT SKYBLUE (-350 1725);
DISPLAY INVISIBLE (-350 1725);
FORCEPROP 2 LAST SIG_NAME A_P12V_STBY_SCALED
J 0
(-725 1635);
DISPLAY 0.617021 (-725 1635);
PAINT ORANGE (-725 1635);
WIRE 16 -1 (-2900 4725)(-2900 4800);
WIRE 16 -1 (-2900 4800)(-2900 4900);
WIRE 16 -1 (-2550 4800)(-2900 4800);
WIRE 16 -1 (-2550 4700)(-2550 4800);
WIRE 16 -1 (-2100 4800)(-2550 4800);
FORCEPROP 0 LAST VOLTAGE +2V
J 0
(-2475 4875);
DISPLAY 1.021277 (-2475 4875);
PAINT SKYBLUE (-2475 4875);
DISPLAY INVISIBLE (-2475 4875);
FORCEPROP 2 LAST SIG_NAME A_P3V3_SCALED
J 0
(-2475 4810);
DISPLAY 0.617021 (-2475 4810);
PAINT ORANGE (-2475 4810);
WIRE 16 -1 (800 1575)(800 1650);
WIRE 16 -1 (800 1650)(800 1750);
WIRE 16 -1 (1600 1650)(800 1650);
FORCEPROP 0 LAST CDS_PHYS_NET_NAME <<OCC_ONLY>>
J 1
(1175 1700);
PAINT ORANGE (1175 1700);
DISPLAY INVISIBLE (1175 1700);
FORCEPROP 0 LAST VOLTAGE +1.2V
J 0
(1425 1725);
DISPLAY 1.021277 (1425 1725);
PAINT SKYBLUE (1425 1725);
DISPLAY INVISIBLE (1425 1725);
FORCEPROP 2 LAST SIG_NAME A_PVNN_STBY_PCH_SENSOR
J 0
(1000 1660);
DISPLAY 0.617021 (1000 1660);
PAINT ORANGE (1000 1660);
WIRE 16 -1 (-650 3275)(-650 3125);
WIRE 16 -1 (-650 3125)(0 3125);
FORCEPROP 0 LAST SIG_NAME FM_BATTERY_SENSE_EN
J 0
(-510 3135);
DISPLAY 0.617021 (-510 3135);
PAINT ORANGE (-510 3135);
FORCEPROP 2 LASTPROP $XRERR UNIQUE?
J 0
(-750 3135);
DISPLAY 0.638298 (-750 3135);
PAINT MONO (-750 3135);
DISPLAY INVISIBLE (-750 3135);
WIRE 16 -1 (-875 3100)(-875 3125);
WIRE 16 -1 (-875 3125)(-650 3125);
WIRE 16 -1 (200 3925)(200 3425);
FORCEPROP 0 LAST VOLTAGE +3V
J 0
(200 3450);
DISPLAY 1.021277 (200 3450);
PAINT SKYBLUE (200 3450);
DISPLAY INVISIBLE (200 3450);
FORCEPROP 0 LAST SIG_NAME P3V_BAT_SOURCE_R
R 1
J 0
(190 3385);
DISPLAY 0.617021 (190 3385);
PAINT ORANGE (190 3385);
FORCEPROP 2 LASTPROP $XRERR UNIQUE?
J 0
(-50 3385);
DISPLAY 0.638298 (-50 3385);
PAINT MONO (-50 3385);
DISPLAY INVISIBLE (-50 3385);
WIRE 16 -1 (-1400 2925)(-1400 2800);
WIRE 16 -1 (-1400 2800)(-1075 2800);
WIRE 16 -1 (-2050 2800)(-1400 2800);
FORCEPROP 0 LAST SIG_NAME FM_BATTERY_SENSE_EN_N
J 0
(-2035 2810);
DISPLAY 0.617021 (-2035 2810);
PAINT ORANGE (-2035 2810);
WIRE 16 -1 (200 4125)(200 4225);
WIRE 16 -1 (-350 4225)(200 4225);
FORCEPROP 2 LAST SIG_NAME A_P3V_BAT_R
J 0
(-360 4235);
DISPLAY 0.617021 (-360 4235);
PAINT ORANGE (-360 4235);
DOT 1 (-4700 4375);
DOT 1 (-4700 4750);
DOT 1 (-4350 4750);
DOT 1 (-1125 1250);
DOT 1 (-2500 1550);
DOT 1 (800 2900);
DOT 1 (400 2900);
DOT 1 (-1400 2800);
DOT 1 (-2850 1175);
DOT 1 (-4825 1600);
DOT 1 (-1125 1625);
DOT 1 (-775 1625);
DOT 1 (800 1650);
DOT 1 (-4825 3400);
DOT 1 (-2550 4800);
DOT 1 (-2900 4800);
DOT 1 (-2900 4450);
DOT 1 (-650 3125);
DOT 1 (-2850 1550);
DOT 1 (-4825 1225);
DOT 1 (-4475 1600);
FORCENOTE
1.31V
(-2400 1650) 0;
DISPLAY LEFT (-2400 1650);
DISPLAY 1.021277 (-2400 1650);
PAINT PURPLE (-2400 1650);
FORCENOTE
1.34V
(-4475 1675) 0;
DISPLAY LEFT (-4475 1675);
DISPLAY 1.021277 (-4475 1675);
PAINT PURPLE (-4475 1675);
FORCENOTE
TP FAB1 CHANGE VALUE OF R1U38, R1U44 AND R1U33 1215
(-5150 2150) 0;
DISPLAY LEFT (-5150 2150);
DISPLAY 1.021277 (-5150 2150);
PAINT RED (-5150 2150);
FORCENOTE
1.05V
(-4500 3475) 0;
DISPLAY LEFT (-4500 3475);
DISPLAY 1.021277 (-4500 3475);
PAINT PURPLE (-4500 3475);
FORCENOTE
TP FAB1 CHANGE VALUE OF R1U28 AND R1U27 1215
(-4800 4150) 0;
DISPLAY LEFT (-4800 4150);
DISPLAY 1.021277 (-4800 4150);
PAINT RED (-4800 4150);
FORCENOTE
1.31V
(-4325 4850) 0;
DISPLAY LEFT (-4325 4850);
DISPLAY 1.021277 (-4325 4850);
PAINT PURPLE (-4325 4850);
FORCENOTE
1.35V
(-725 1700) 0;
DISPLAY LEFT (-725 1700);
DISPLAY 1.021277 (-725 1700);
PAINT PURPLE (-725 1700);
FORCENOTE
1.34V
(-2475 4900) 0;
DISPLAY LEFT (-2475 4900);
DISPLAY 1.021277 (-2475 4900);
PAINT PURPLE (-2475 4900);
FORCENOTE
0.85V~1V
(1150 1725) 0;
DISPLAY LEFT (1150 1725);
DISPLAY 1.021277 (1150 1725);
PAINT PURPLE (1150 1725);
FORCENOTE
1V
(775 2975) 0;
DISPLAY LEFT (775 2975);
DISPLAY 1.021277 (775 2975);
PAINT PURPLE (775 2975);
FORCENOTE
ROOM=SM_HM
(-5144 797) 0;
DISPLAY LEFT (-5144 797);
DISPLAY 0.617021 (-5144 797);
PAINT PURPLE (-5144 797);
QUIT
